PAGE 6. BLADE 2 ETHERNET AIRMAX AND SFP+
TRAY BACKPLANE ASSEMBLY E1020
PAGE 2. BLADE 1 PCIE AND TBP MEZZ
PAGE 3. BLADE 2 PCIE AND TBP MEZZ
PAGE 4. BLADE 1 ETHERNET AIRMAX AND SFP+
11/24/14-1 INITIAL RELEASE (POC)
PAGE 1. TITLE PAGE
PAGE 5. BLADE 1 ETHERNET QSFP+
PAGE 7. BLADE 2 ETHERNET QSFP+
PAGE 8. BLADE 1 SAS
PAGE 9. BLADE 2 SAS
PAGE 11. MECHANICAL
PAGE 10. EDGE FINGERS AND POWER
1 11 
TRAY BACKPLANE ASSEMBLY V2
CLOUD SERVER INFRASTRUCTURE ENGINEERING
11/24/2014
-1
1/11
CSA
OFPAGE:
REVISION:
DATE:PROJECT TITLE:
DRAWING NUMBER:
D
C
B
A
12345678
A
B
C
D
REVISIONS
REV DESCRIPTION DATE
8 7 6 5 4 3 2 1
PAGE 6. BLADE 2 ETHERNET AIRMAX AND SFP+
TRAY BACKPLANE ASSEMBLY E1020
PAGE 2. BLADE 1 PCIE AND TBP MEZZ
PAGE 3. BLADE 2 PCIE AND TBP MEZZ
PAGE 4. BLADE 1 ETHERNET AIRMAX AND SFP+
11/24/14-1 INITIAL RELEASE (POC)
PAGE 1. TITLE PAGE
PAGE 5. BLADE 1 ETHERNET QSFP+
PAGE 7. BLADE 2 ETHERNET QSFP+
PAGE 8. BLADE 1 SAS
PAGE 9. BLADE 2 SAS
PAGE 11. MECHANICAL
PAGE 10. EDGE FINGERS AND POWER
1 11 
TRAY BACKPLANE ASSEMBLY V2
CLOUD SERVER INFRASTRUCTURE ENGINEERING
11/24/2014
-1
1/11
CSA
OFPAGE:
REVISION:
DATE:PROJECT TITLE:
DRAWING NUMBER:
D
C
B
A
12345678
A
B
C
D
REVISIONS
REV DESCRIPTION DATE
8 7 6 5 4 3 2 1



AIRMAX VS2 5X10 SEAF CONNECTOR
AIRMAX POWER CONNECTOR
112
CLOUD SERVER INFRASTRUCTURE ENGINEERING
 
11/24/2014
-12/11
PCIE_T2B_B1_RX_DN<1>
PCIE_T2B_B1_RX_DP<2> B6
J4
PCIE_B2T_B1_TX_DP<5>
PCIE_B2T_B1_TX_DP<7>
10B7 
PCIE_T2B_B1_RX_DP<4>
17
1 of 4
PCIE_CFG_B1_ID1
PCIE_RESET_B1_N<1>
PCIE_RESET_B1_N<2> O7
PCIE_B2T_B1_TX_DN<10>
PCIE_B2T_B1_TX_DN<12>
PCIE_B2T_B1_TX_DN<14>
P12V_MEZZ_B1
PCIE_T2B_B1_RX_DP<8>
PCIE_T2B_B1_RX_DN<10>
PCIE_T2B_B1_RX_DP<14>
10%0.1 UF
402X5R
25 V
C41
2
402
25 VX5R
0.1 UF10%
C31
2
3D
3E
3F
10%1 UF 10%25 VX7R
603
CONN
PCIE_T2B_B1_RX_DN<9>
PCIE_T2B_B1_RX_DP<9>
4D5 
10B7 
10A7 
10A7 
10B7 
PCIE_T2B_B1_RX_DP<7>
A2
BLADE_MATED_B1_N<0>
SERIAL_B1_RX2
PCIE_T2B_B1_RX_DN<4>
PCIE_T2B_B1_RX_DN<6>
PCIE_T2B_B1_RX_DP<6>
2 1R85
2
1 C2
2
1 C1
4F
4E
4D
4C
4B
4A
3C
3B
3A
2F
2E
2D
2C
2B
2A
1F
1E
1D
1C
1B
1A
J4
9695
8887
80
8
79
7271
7
6463
5655
4847
4039
3231
2423
160
16
159
152151
15
144143
136135
128127
120119
112111
104103
J2
9493
8685
7877
7069
6261
6
5453
5
4645
3837
3029
2221
158157
150149
142141
14
134133
13
126125
118117
110109
102101
J2
99
9291
8483
7675
6867
6059
5251
4443
4
3635
3
2827
2019
156155
148147
140139
132131
124123
12
116115
11
108107
100
J2
9897
90
9
89
8281
7473
6665
5857
5049
4241
3433
2625
2
18
154153
146145
138137
130129
122121
114113
106105
10
1
J2
P8
P6
P4
P2
P10
O9
O8
O6
O5
O4
O3
O2
O10
O1
N9
N8
N7
N6
N5
N4
N3
N2
N10
N1
M9
M8
M7
M6
M5
M4
M3
M2
M10
M1
L9
L8
L7
L6
L5
L4
L3
L2
L10
L1
K9
K8
K7
K6
K5
K4
K3
K2
K10
K1
J9
J8
J7
J6
J5
J3
J2
J10
J1
I9
I8
I7
I6
I5
I4
I3
I2
I10
I1
H9
H8
H7
H6
H5
H4
H3
H2
H10
H1
G9
G8
G7
G6
G5
G4
G3
G2
G10
G1
F9
F8
F7
F6
F5
F4
F3
F2
F10
F1
E9
E8
E7
E6
E5
E4
E3
E2
E10
E1
D9
D8
D7
D6
D5
D4
D3
D2
D10
D1
C9
C8
C7
C6
C5
C4
C3
C2
C10
C1
B9
B8
B7
B5
B4
B3
B2
B10
B1
A9
A8
A7
A6
A5
A4
A3
A10
A1
J1
PSU_B1_ALERT_N
CLK_100M_B1_N<2>
SERIAL_B1_TX2
PCIE_T2B_B1_RX_DN<14>
PCIE_T2B_B1_RX_DN<8>
PCIE_T2B_B1_RX_DP<10>
PCIE_T2B_B1_RX_DP<12>
PCIE_T2B_B1_RX_DN<12>
MEZZ_B1_SCL
PCIE_CFG_B1_ID1
CLK_100M_B1_P<1>
CLK_100M_B1_N<1>
PCIE_T2B_B1_RX_DN<11>
PCIE_T2B_B1_RX_DP<11>
PCIE_T2B_B1_RX_DP<13>
PCIE_T2B_B1_RX_DN<13>
PCIE_T2B_B1_RX_DN<15>
PCIE_T2B_B1_RX_DP<15>
PCIE_T2B_B1_RX_DP<0>
PCIE_T2B_B1_RX_DN<0>
PCIE_T2B_B1_RX_DN<2>
PCIE_T2B_B1_RX_DP<2>
CLK_100M_B1_P<0>
CLK_100M_B1_N<0>
PCIE_T2B_B1_RX_DN<1>
PCIE_T2B_B1_RX_DP<1>
PCIE_T2B_B1_RX_DN<3>
PCIE_T2B_B1_RX_DP<3>
PCIE_T2B_B1_RX_DP<5>
PCIE_T2B_B1_RX_DN<5>
PCIE_T2B_B1_RX_DN<7>
PCIE_T2B_B1_RX_DP<7>
PCIE_WAKE_B1_N
PCIE_RESET_B1_N<2>
PCIE_RESET_B1_N<1>
PCIE_B2T_B1_TX_DN<8>
PCIE_B2T_B1_TX_DP<8>
PCIE_B2T_B1_TX_DN<10>
PCIE_B2T_B1_TX_DP<10>
PCIE_B2T_B1_TX_DP<12>
PCIE_B2T_B1_TX_DN<12>
PCIE_B2T_B1_TX_DN<14>
PCIE_B2T_B1_TX_DP<14>
MEZZ_PRESENT_B1_N
CLK_100M_B1_P<3>
CLK_100M_B1_N<3>
PCIE_RESET_B1_N<3>
PCIE_B2T_B1_TX_DN<9>
PCIE_B2T_B1_TX_DP<9>
PCIE_B2T_B1_TX_DN<11>
PCIE_B2T_B1_TX_DP<11>
PCIE_B2T_B1_TX_DP<13>
PCIE_B2T_B1_TX_DN<13>
PCIE_B2T_B1_TX_DN<15>
PCIE_B2T_B1_TX_DP<15>
MEZZ_B1_EN
PCIE_CFG_B1_ID0
PCIE_B2T_B1_TX_DP<0>
PCIE_B2T_B1_TX_DN<0>
PCIE_B2T_B1_TX_DN<2>
PCIE_B2T_B1_TX_DP<2>
PCIE_B2T_B1_TX_DP<4>
PCIE_B2T_B1_TX_DN<4>
PCIE_B2T_B1_TX_DN<6>
PCIE_B2T_B1_TX_DP<6>
MEZZ_B1_SDA
PCIE_RESET_B1_N<0>
CLK_100M_B1_P<2>
CLK_100M_B1_N<2>
PCIE_B2T_B1_TX_DN<1>
PCIE_B2T_B1_TX_DP<1>
PCIE_B2T_B1_TX_DN<3>
PCIE_B2T_B1_TX_DP<3>
PCIE_B2T_B1_TX_DP<5>
PCIE_B2T_B1_TX_DN<5>
PCIE_B2T_B1_TX_DN<7>
PCIE_B2T_B1_TX_DP<7>
P12V_MEZZ_B1
VOLTAGE=12
2 of 4
SM
CONN
X886612-001
CONN
X886612-001
SM
P12V_MEZZ_B1
4 of 4
X886612-001
SM
CONN
3 of 4
X886612-001
SM
CONN
CLK_100M_B1_P<2>
P5V_USB_B1
CLK_100M_B1_N<1>
CLK_100M_B1_P<1>
USB_B1_N
USB_B1_P
CLK_100M_B1_N<0>
MEZZ_PRESENT_B1_N
MEZZ_B1_EN
PCIE_WAKE_B1_N
NC
MEZZ_B1_SCL
PCIE_CFG_B1_ID0
PCIE_RESET_B1_N<3>
PCIE_T2B_B1_RX_DN<8>
PCIE_T2B_B1_RX_DN<10>
PCIE_T2B_B1_RX_DN<12>
PCIE_T2B_B1_RX_DN<14>
PCIE_T2B_B1_RX_DP<8>
PCIE_T2B_B1_RX_DN<9>
PCIE_T2B_B1_RX_DP<10>
PCIE_T2B_B1_RX_DN<11>
PCIE_T2B_B1_RX_DP<12>
PCIE_T2B_B1_RX_DN<13>
PCIE_T2B_B1_RX_DP<14>
PCIE_T2B_B1_RX_DN<15>
PCIE_T2B_B1_RX_DP<9>
PCIE_T2B_B1_RX_DP<11>
PCIE_T2B_B1_RX_DP<13>
PCIE_T2B_B1_RX_DP<15>
PCIE_T2B_B1_RX_DN<0>
PCIE_T2B_B1_RX_DN<2>
PCIE_T2B_B1_RX_DN<4>
PCIE_T2B_B1_RX_DN<6>
PCIE_T2B_B1_RX_DP<0>
PCIE_T2B_B1_RX_DN<3>
PCIE_T2B_B1_RX_DP<4>
PCIE_T2B_B1_RX_DN<5>
PCIE_T2B_B1_RX_DP<6>
PCIE_T2B_B1_RX_DN<7>
PCIE_T2B_B1_RX_DP<5>
CLK_100M_B1_P<0>
PCIE_T2B_B1_RX_DP<1>
PCIE_T2B_B1_RX_DP<3>
PCIE_RESET_B1_N<0>
MEZZ_B1_SDA
PCIE_B2T_B1_TX_DP<3>
PCIE_B2T_B1_TX_DP<1>
CLK_100M_B1_P<3>
PCIE_B2T_B1_TX_DN<7>
PCIE_B2T_B1_TX_DP<6>
PCIE_B2T_B1_TX_DN<5>
PCIE_B2T_B1_TX_DP<4>
PCIE_B2T_B1_TX_DN<3>
PCIE_B2T_B1_TX_DN<1>
PCIE_B2T_B1_TX_DP<2>
PCIE_B2T_B1_TX_DP<0>
CLK_100M_B1_N<3>
PCIE_B2T_B1_TX_DN<6>
PCIE_B2T_B1_TX_DN<4>
PCIE_B2T_B1_TX_DN<2>
PCIE_B2T_B1_TX_DN<0>
PCIE_B2T_B1_TX_DP<15>
PCIE_B2T_B1_TX_DP<13>
PCIE_B2T_B1_TX_DP<11>
PCIE_B2T_B1_TX_DP<9>
PCIE_B2T_B1_TX_DN<15>
PCIE_B2T_B1_TX_DP<14>
PCIE_B2T_B1_TX_DN<13>
PCIE_B2T_B1_TX_DN<11>
PCIE_B2T_B1_TX_DP<12>
PCIE_B2T_B1_TX_DP<10>
PCIE_B2T_B1_TX_DN<9>
PCIE_B2T_B1_TX_DP<8>
PCIE_B2T_B1_TX_DN<8>
CONN
TH
X886847-001
P12V_MEZZ_B1
BLADE_MATED_B1_N<0>
100 OHM603
X863844-001
TH
25 V
603X7R
P12V
1 UF
1%CH
10B7 
8 7 6 5 4 3 2 1
D
C
B
A
DATE:
OFREVISION:DRAWING NUMBER:
12345678
A
B
C
D
PAGE:
IN
OUT
BI
BI
OUT
AIRMAX24P
4F
4E
4D
4C
4B
4A
3F
3E
3D
3C
3B
3A
2F
2E
2D
2C
2B
2A
1F
1E
1D
1C
1B
1A
8X20RCPT
159
135
143
151
127
119
95
103
111
87
79
71
55
63
47
39
31
15
23
7
160
136
144
152
128
120
112
104
96
80
88
72
64
56
40
48
32
24
16
8
8X20RCPT
157
149
133
141
117
125
109
101
93
85
77
69
53
61
45
37
29
13
21
5
158
150
134
142
118
126
110
102
94
78
86
70
62
54
38
46
30
22
14
6
8X20RCPT
27
155
147
131
139
115
123
107
99
91
83
75
67
51
59
43
35
11
19
3
156
148
132
140
116
124
108
100
92
76
84
68
60
52
36
44
28
20
12
4
8X20RCPT
153
145
129
137
113
121
105
97
89
81
73
65
49
57
41
33
25
9
17
1
154
146
130
138
114
122
106
98
90
74
82
66
58
50
34
42
26
18
10
2
AIRMAX155
P8
P6
P10
P4
P2
H10
H9
G10
G9
F10
F9
E10
E9
D10
D9
C10
C9
B10
B9
H8
H7
H6
H5
H4
H3
H2
H1
G8
G7
G6
G5
G4
G3
G2
G1
F8
F7
F6
F5
F4
F3
F2
F1
E8
E7
E6
E5
E4
E3
E2
E1
D8
D7
D6
D5
D4
D3
D2
D1
C8
C7
C6
C5
C4
C3
C2
C1
B8
B7
B6
B5
B4
B3
B2
B1
A3
A2
A1
A9
A8
A7
A6
A5
A4
A10
I1
I3
I2
I4
I5
I6
I7
I8
I9
I10
J1
J2
J3
J4
J5
J6
J8
J7
J10
J9
K1
K2
K3
K4
K5
K7
K6
K8
K9
K10
L1
L2
L3
L4
L5
L6
L7
L9
L8
L10
M1
M2
M3
M4
M5
M6
M8
M7
M9
M10
N1
N2
N3
N5
N4
N6
N7
N8
N10
N9
O2
O1
O3
O4
O5
O6
O7
O9
O8
O10
AIRMAX VS2 5X10 SEAF CONNECTOR
AIRMAX POWER CONNECTOR
112
CLOUD SERVER INFRASTRUCTURE ENGINEERING
 
11/24/2014
-12/11
1 of 4
P12V_MEZZ_B1
10%0.1 UF
402X5R
25 V
402
25 VX5R
0.1 UF10%10%1 UF 10%25 V
X7R
603
CONN
P12V_MEZZ_B1
VOLTAGE=12
2 of 4
SM
CONN
X886612-001
CONN
X886612-001
SM
P12V_MEZZ_B1
4 of 4
X886612-001
SM
CONN
3 of 4
X886612-001
SM
CONN
CONN
TH
X886847-001
P12V_MEZZ_B1
100 OHM603
X863844-001
TH
25 V
603X7R
P12V
1 UF
1%CH
C4C3
R85
C2C1
J4
J2
J2
J2
J2
J1
10B7 4D5 
10B7 
10A7 
10A7 
10B7 
10B7 
PCIE_T2B_B1_RX_DN<1>
PCIE_T2B_B1_RX_DP<2>
PCIE_B2T_B1_TX_DP<5>
PCIE_B2T_B1_TX_DP<7>
PCIE_T2B_B1_RX_DP<4>
PCIE_CFG_B1_ID1
PCIE_RESET_B1_N<1>
PCIE_RESET_B1_N<2>
PCIE_B2T_B1_TX_DN<10>
PCIE_B2T_B1_TX_DN<12>
PCIE_B2T_B1_TX_DN<14>
PCIE_T2B_B1_RX_DP<8>
PCIE_T2B_B1_RX_DN<10>
PCIE_T2B_B1_RX_DP<14>
PCIE_T2B_B1_RX_DN<9>
PCIE_T2B_B1_RX_DP<9>
PCIE_T2B_B1_RX_DP<7>
BLADE_MATED_B1_N<0>
SERIAL_B1_RX2
PCIE_T2B_B1_RX_DN<4>
PCIE_T2B_B1_RX_DN<6>
PCIE_T2B_B1_RX_DP<6>
PSU_B1_ALERT_N
CLK_100M_B1_N<2>
SERIAL_B1_TX2
PCIE_T2B_B1_RX_DN<14>
PCIE_T2B_B1_RX_DN<8>
PCIE_T2B_B1_RX_DP<10>
PCIE_T2B_B1_RX_DP<12>
PCIE_T2B_B1_RX_DN<12>
MEZZ_B1_SCL
PCIE_CFG_B1_ID1
CLK_100M_B1_P<1>
CLK_100M_B1_N<1>
PCIE_T2B_B1_RX_DN<11>
PCIE_T2B_B1_RX_DP<11>
PCIE_T2B_B1_RX_DP<13>
PCIE_T2B_B1_RX_DN<13>
PCIE_T2B_B1_RX_DN<15>
PCIE_T2B_B1_RX_DP<15>
PCIE_T2B_B1_RX_DP<0>
PCIE_T2B_B1_RX_DN<0>
PCIE_T2B_B1_RX_DN<2>
PCIE_T2B_B1_RX_DP<2>
CLK_100M_B1_P<0>
CLK_100M_B1_N<0>
PCIE_T2B_B1_RX_DN<1>
PCIE_T2B_B1_RX_DP<1>
PCIE_T2B_B1_RX_DN<3>
PCIE_T2B_B1_RX_DP<3>
PCIE_T2B_B1_RX_DP<5>
PCIE_T2B_B1_RX_DN<5>
PCIE_T2B_B1_RX_DN<7>
PCIE_T2B_B1_RX_DP<7>
PCIE_WAKE_B1_N
PCIE_RESET_B1_N<2>
PCIE_RESET_B1_N<1>
PCIE_B2T_B1_TX_DN<8>
PCIE_B2T_B1_TX_DP<8>
PCIE_B2T_B1_TX_DN<10>
PCIE_B2T_B1_TX_DP<10>
PCIE_B2T_B1_TX_DP<12>
PCIE_B2T_B1_TX_DN<12>
PCIE_B2T_B1_TX_DN<14>
PCIE_B2T_B1_TX_DP<14>
MEZZ_PRESENT_B1_N
CLK_100M_B1_P<3>
CLK_100M_B1_N<3>
PCIE_RESET_B1_N<3>
PCIE_B2T_B1_TX_DN<9>
PCIE_B2T_B1_TX_DP<9>
PCIE_B2T_B1_TX_DN<11>
PCIE_B2T_B1_TX_DP<11>
PCIE_B2T_B1_TX_DP<13>
PCIE_B2T_B1_TX_DN<13>
PCIE_B2T_B1_TX_DN<15>
PCIE_B2T_B1_TX_DP<15>
MEZZ_B1_EN
PCIE_CFG_B1_ID0
PCIE_B2T_B1_TX_DP<0>
PCIE_B2T_B1_TX_DN<0>
PCIE_B2T_B1_TX_DN<2>
PCIE_B2T_B1_TX_DP<2>
PCIE_B2T_B1_TX_DP<4>
PCIE_B2T_B1_TX_DN<4>
PCIE_B2T_B1_TX_DN<6>
PCIE_B2T_B1_TX_DP<6>
MEZZ_B1_SDA
PCIE_RESET_B1_N<0>
CLK_100M_B1_P<2>
CLK_100M_B1_N<2>
PCIE_B2T_B1_TX_DN<1>
PCIE_B2T_B1_TX_DP<1>
PCIE_B2T_B1_TX_DN<3>
PCIE_B2T_B1_TX_DP<3>
PCIE_B2T_B1_TX_DP<5>
PCIE_B2T_B1_TX_DN<5>
PCIE_B2T_B1_TX_DN<7>
PCIE_B2T_B1_TX_DP<7>
CLK_100M_B1_P<2>
P5V_USB_B1
CLK_100M_B1_N<1>
CLK_100M_B1_P<1>
USB_B1_N
USB_B1_P
CLK_100M_B1_N<0>
MEZZ_PRESENT_B1_N
MEZZ_B1_EN
PCIE_WAKE_B1_N
NC
MEZZ_B1_SCL
PCIE_CFG_B1_ID0
PCIE_RESET_B1_N<3>
PCIE_T2B_B1_RX_DN<8>
PCIE_T2B_B1_RX_DN<10>
PCIE_T2B_B1_RX_DN<12>
PCIE_T2B_B1_RX_DN<14>
PCIE_T2B_B1_RX_DP<8>
PCIE_T2B_B1_RX_DN<9>
PCIE_T2B_B1_RX_DP<10>
PCIE_T2B_B1_RX_DN<11>
PCIE_T2B_B1_RX_DP<12>
PCIE_T2B_B1_RX_DN<13>
PCIE_T2B_B1_RX_DP<14>
PCIE_T2B_B1_RX_DN<15>
PCIE_T2B_B1_RX_DP<9>
PCIE_T2B_B1_RX_DP<11>
PCIE_T2B_B1_RX_DP<13>
PCIE_T2B_B1_RX_DP<15>
PCIE_T2B_B1_RX_DN<0>
PCIE_T2B_B1_RX_DN<2>
PCIE_T2B_B1_RX_DN<4>
PCIE_T2B_B1_RX_DN<6>
PCIE_T2B_B1_RX_DP<0>
PCIE_T2B_B1_RX_DN<3>
PCIE_T2B_B1_RX_DP<4>
PCIE_T2B_B1_RX_DN<5>
PCIE_T2B_B1_RX_DP<6>
PCIE_T2B_B1_RX_DN<7>
PCIE_T2B_B1_RX_DP<5>
CLK_100M_B1_P<0>
PCIE_T2B_B1_RX_DP<1>
PCIE_T2B_B1_RX_DP<3>
PCIE_RESET_B1_N<0>
MEZZ_B1_SDA
PCIE_B2T_B1_TX_DP<3>
PCIE_B2T_B1_TX_DP<1>
CLK_100M_B1_P<3>
PCIE_B2T_B1_TX_DN<7>
PCIE_B2T_B1_TX_DP<6>
PCIE_B2T_B1_TX_DN<5>
PCIE_B2T_B1_TX_DP<4>
PCIE_B2T_B1_TX_DN<3>
PCIE_B2T_B1_TX_DN<1>
PCIE_B2T_B1_TX_DP<2>
PCIE_B2T_B1_TX_DP<0>
CLK_100M_B1_N<3>
PCIE_B2T_B1_TX_DN<6>
PCIE_B2T_B1_TX_DN<4>
PCIE_B2T_B1_TX_DN<2>
PCIE_B2T_B1_TX_DN<0>
PCIE_B2T_B1_TX_DP<15>
PCIE_B2T_B1_TX_DP<13>
PCIE_B2T_B1_TX_DP<11>
PCIE_B2T_B1_TX_DP<9>
PCIE_B2T_B1_TX_DN<15>
PCIE_B2T_B1_TX_DP<14>
PCIE_B2T_B1_TX_DN<13>
PCIE_B2T_B1_TX_DN<11>
PCIE_B2T_B1_TX_DP<12>
PCIE_B2T_B1_TX_DP<10>
PCIE_B2T_B1_TX_DN<9>
PCIE_B2T_B1_TX_DP<8>
PCIE_B2T_B1_TX_DN<8>
BLADE_MATED_B1_N<0>
B6
J4
17
O7
1
2
1
2
3D
3E
3F
A2
2 1
2
1
2
1
4F
4E
4D
4C
4B
4A
3C
3B
3A
2F
2E
2D
2C
2B
2A
1F
1E
1D
1C
1B
1A
9695
8887
80
8
79
7271
7
6463
5655
4847
4039
3231
2423
160
16
159
152151
15
144143
136135
128127
120119
112111
104103
9493
8685
7877
7069
6261
6
5453
5
4645
3837
3029
2221
158157
150149
142141
14
134133
13
126125
118117
110109
102101
99
9291
8483
7675
6867
6059
5251
4443
4
3635
3
2827
2019
156155
148147
140139
132131
124123
12
116115
11
108107
100
9897
90
9
89
8281
7473
6665
5857
5049
4241
3433
2625
2
18
154153
146145
138137
130129
122121
114113
106105
10
1
P8
P6
P4
P2
P10
O9
O8
O6
O5
O4
O3
O2
O10
O1
N9
N8
N7
N6
N5
N4
N3
N2
N10
N1
M9
M8
M7
M6
M5
M4
M3
M2
M10
M1
L9
L8
L7
L6
L5
L4
L3
L2
L10
L1
K9
K8
K7
K6
K5
K4
K3
K2
K10
K1
J9
J8
J7
J6
J5
J3
J2
J10
J1
I9
I8
I7
I6
I5
I4
I3
I2
I10
I1
H9
H8
H7
H6
H5
H4
H3
H2
H10
H1
G9
G8
G7
G6
G5
G4
G3
G2
G10
G1
F9
F8
F7
F6
F5
F4
F3
F2
F10
F1
E9
E8
E7
E6
E5
E4
E3
E2
E10
E1
D9
D8
D7
D6
D5
D4
D3
D2
D10
D1
C9
C8
C7
C6
C5
C4
C3
C2
C10
C1
B9
B8
B7
B5
B4
B3
B2
B10
B1
A9
A8
A7
A6
A5
A4
A3
A10
A1
IN
OUT
BI
BI
OUT
AIRMAX24P
4F
4E
4D
4C
4B
4A
3F
3E
3D
3C
3B
3A
2F
2E
2D
2C
2B
2A
1F
1E
1D
1C
1B
1A
8X20RCPT
159
135
143
151
127
119
95
103
111
87
79
71
55
63
47
39
31
15
23
7
160
136
144
152
128
120
112
104
96
80
88
72
64
56
40
48
32
24
16
8
8X20RCPT
157
149
133
141
117
125
109
101
93
85
77
69
53
61
45
37
29
13
21
5
158
150
134
142
118
126
110
102
94
78
86
70
62
54
38
46
30
22
14
6
8X20RCPT
27
155
147
131
139
115
123
107
99
91
83
75
67
51
59
43
35
11
19
3
156
148
132
140
116
124
108
100
92
76
84
68
60
52
36
44
28
20
12
48X20RCPT
153
145
129
137
113
121
105
97
89
81
73
65
49
57
41
33
25
9
17
1
154
146
130
138
114
122
106
98
90
74
82
66
58
50
34
42
26
18
10
2
AIRMAX155
P8
P6
P10
P4
P2
H10
H9
G10
G9
F10
F9
E10
E9
D10
D9
C10
C9
B10
B9
H8
H7
H6
H5
H4
H3
H2
H1
G8
G7
G6
G5
G4
G3
G2
G1
F8
F7
F6
F5
F4
F3
F2
F1
E8
E7
E6
E5
E4
E3
E2
E1
D8
D7
D6
D5
D4
D3
D2
D1
C8
C7
C6
C5
C4
C3
C2
C1
B8
B7
B6
B5
B4
B3
B2
B1
A3
A2
A1
A9
A8
A7
A6
A5
A4
A10
I1
I3
I2
I4
I5
I6
I7
I8
I9
I10
J1
J2
J3
J4
J5
J6
J8
J7
J10
J9
K1
K2
K3
K4
K5
K7
K6
K8
K9
K10
L1
L2
L3
L4
L5
L6
L7
L9
L8
L10
M1
M2
M3
M4
M5
M6
M8
M7
M9
M10
N1
N2
N3
N5
N4
N6
N7
N8
N10
N9
O2
O1
O3
O4
O5
O6
O7
O9
O8
O10
8 7 6 5 4 3 2 1
D
C
B
A
DATE:
OFREVISION:DRAWING NUMBER:
12345678
A
B
C
D
PAGE:



SEAF CONNECTOR
AIRMAX POWER CONNECTOR
AIRMAX VS2 5X10
113
CLOUD SERVER INFRASTRUCTURE ENGINEERING
 
11/24/2014
-13/11
2
C14
BLADE_MATED_B2_N<0>
PCIE_RESET_B2_N<0>
MEZZ_B2_SDA
NC
PCIE_WAKE_B2_N
PCIE_CFG_B2_ID1
PCIE_RESET_B2_N<1>
VOLTAGE=0
P12V
USB_B2_P
USB_B2_N
P5V_USB_B2
CLK_100M_B2_P<2>
PCIE_T2B_B2_RX_DN<7>
PCIE_B2T_B2_TX_DN<13>
PCIE_B2T_B2_TX_DP<11>
PCIE_B2T_B2_TX_DN<9>
PCIE_B2T_B2_TX_DP<8>
TH
X7R603X7R
1 UF
603
TH
X886847-001
100 OHM CH1%603
BLADE_MATED_B2_N<0>
CLK_100M_B2_N<0>
PCIE_B2T_B2_TX_DN<11>
CONN
X863844-001
PCIE_T2B_B2_RX_DP<6>
PCIE_B2T_B2_TX_DP<10>
PCIE_B2T_B2_TX_DP<12>
PCIE_T2B_B2_RX_DN<5>
PCIE_T2B_B2_RX_DP<4>
PCIE_T2B_B2_RX_DN<3>
PCIE_T2B_B2_RX_DP<2>
PCIE_T2B_B2_RX_DN<1>
PCIE_T2B_B2_RX_DP<0>
PCIE_T2B_B2_RX_DN<6>
PCIE_T2B_B2_RX_DN<4>
PCIE_T2B_B2_RX_DN<2>
PCIE_T2B_B2_RX_DN<0>
PCIE_T2B_B2_RX_DP<15>
PCIE_T2B_B2_RX_DP<13>
PCIE_T2B_B2_RX_DP<11>
PCIE_T2B_B2_RX_DP<9>
CLK_100M_B2_P<1>
PCIE_T2B_B2_RX_DN<15>
PCIE_T2B_B2_RX_DP<14>
PCIE_T2B_B2_RX_DN<13>
PCIE_T2B_B2_RX_DP<12>
PCIE_T2B_B2_RX_DN<11>
PCIE_T2B_B2_RX_DP<10>
PCIE_T2B_B2_RX_DN<9>
PCIE_T2B_B2_RX_DP<8>
CLK_100M_B2_N<1>
PCIE_T2B_B2_RX_DN<14>
PCIE_T2B_B2_RX_DN<12>
PCIE_T2B_B2_RX_DN<10>
PCIE_T2B_B2_RX_DN<8>
PCIE_RESET_B2_N<2>
MEZZ_B2_EN
MEZZ_PRESENT_B2_N
PCIE_RESET_B2_N<3>
PCIE_CFG_B2_ID0
MEZZ_B2_SCL
CLK_100M_B2_N<2>
SERIAL_B2_TX2
3 of 4
X886612-001
SM
CONN
P12V_MEZZ_B2
4 of 4
X886612-001
SM
CONN
X886612-001
SM
CONN
1 of 4
P12V_MEZZ_B2
X886612-001
SM
CONN
2 of 4
P12V_MEZZ_B2
VOLTAGE=12
PCIE_B2T_B2_TX_DP<7>
PCIE_B2T_B2_TX_DN<7>
PCIE_B2T_B2_TX_DN<5>
PCIE_B2T_B2_TX_DP<5>
PCIE_B2T_B2_TX_DP<3>
PCIE_B2T_B2_TX_DN<3>
PCIE_B2T_B2_TX_DP<1>
PCIE_B2T_B2_TX_DN<1>
CLK_100M_B2_N<2>
CLK_100M_B2_P<2>
PCIE_RESET_B2_N<0>
MEZZ_B2_SDA
PCIE_B2T_B2_TX_DP<6>
PCIE_B2T_B2_TX_DN<6>
PCIE_B2T_B2_TX_DN<4>
PCIE_B2T_B2_TX_DP<4>
PCIE_B2T_B2_TX_DP<2>
PCIE_B2T_B2_TX_DN<2>
PCIE_B2T_B2_TX_DN<0>
PCIE_B2T_B2_TX_DP<0>
PCIE_CFG_B2_ID0
MEZZ_B2_EN
PCIE_B2T_B2_TX_DP<15>
PCIE_B2T_B2_TX_DN<15>
PCIE_B2T_B2_TX_DN<13>
PCIE_B2T_B2_TX_DP<13>
PCIE_B2T_B2_TX_DP<11>
PCIE_B2T_B2_TX_DN<11>
PCIE_B2T_B2_TX_DP<9>
PCIE_B2T_B2_TX_DN<9>
PCIE_RESET_B2_N<3>
CLK_100M_B2_N<3>
CLK_100M_B2_P<3>
MEZZ_PRESENT_B2_N
PCIE_B2T_B2_TX_DP<14>
PCIE_B2T_B2_TX_DN<14>
PCIE_B2T_B2_TX_DN<12>
PCIE_B2T_B2_TX_DP<12>
PCIE_B2T_B2_TX_DP<10>
PCIE_B2T_B2_TX_DN<10>
PCIE_B2T_B2_TX_DP<8>
PCIE_B2T_B2_TX_DN<8>
PCIE_RESET_B2_N<1>
PCIE_RESET_B2_N<2>
PCIE_WAKE_B2_N
PCIE_T2B_B2_RX_DP<7>
PCIE_T2B_B2_RX_DN<7>
PCIE_T2B_B2_RX_DN<5>
PCIE_T2B_B2_RX_DP<5>
PCIE_T2B_B2_RX_DP<3>
PCIE_T2B_B2_RX_DN<3>
PCIE_T2B_B2_RX_DP<1>
CLK_100M_B2_N<0>
CLK_100M_B2_P<0>
PCIE_T2B_B2_RX_DP<6>
PCIE_T2B_B2_RX_DN<6>
PCIE_T2B_B2_RX_DN<4>
PCIE_T2B_B2_RX_DP<2>
PCIE_T2B_B2_RX_DN<15>
PCIE_T2B_B2_RX_DP<11>
PCIE_T2B_B2_RX_DP<9>
CLK_100M_B2_N<1>
CLK_100M_B2_P<1>
PCIE_CFG_B2_ID1
MEZZ_B2_SCL
PCIE_T2B_B2_RX_DP<14>
PCIE_T2B_B2_RX_DN<12>
PCIE_T2B_B2_RX_DP<12>
PCIE_T2B_B2_RX_DP<10>
PCIE_T2B_B2_RX_DN<8>
PCIE_T2B_B2_RX_DP<8>
PCIE_T2B_B2_RX_DN<14>
PSU_B2_ALERT_N
J14
103 104
111 112
119 120
127 128
135 136
143 144
15
151 152
159
16
160
23 24
31 32
39 40
47 48
55 56
63 64
7
71 72
79
8
80
87 88
95 96
C131
2
J16
1A
1B
1C
1D
1E
1F
2A
2B
2C
2D
2E
2F
3B
3C
3D
3E
3F
4A
4B
4C
4D
4E
4F
J14
101 102
109 110
117 118
125 126
13
133 134
14
141 142
149 150
157 158
21 22
29 30
37 38
45 46
5
53 54
6
61 62
69 70
77 78
85 86
93 94
1
J14
100
107 108
11
115 116
12
123 124
131 132
139 140
147 148
155 156
19 20
27 28
3
35 36
4
43 44
51 52
59 60
67 68
75 76
83 84
91 92
99
J14
1
10
105 106
113 114
121 122
129 130
137 138
145 146
153 154
17 18
2
25 26
33 34
41 42
49 50
57 58
65 66
73 74
81 82
89
9
90
97 98
A2
A3
A4
A5
A6
A7
A8
A9
B1
B2
B3
B4
B5
B6
B7
C1
C2
C3
C4
C5
C6
C7
C8
C9
D10
D3
D4
D5
D6
D7
D8
D9
E1
E10
E2
E3
E4
E5
E6
E7
E8
E9
F1
F10
F2
F3
F4
F5
F6
F7
F8
F9
G1
G10
G2
G3
G4
G5
G6
G7
G8
G9
H1
H10
H2
H3
H4
H5
H6
H7
H8
H9
I1
I2
I3
I4
I5
I8
I9
J10
J2
J3
J4
J8
J9
K1
K10
K2
K3
K4
K5
K6
K7
K9
L1
L10
L2
L3
L4
L5
L6
L7
L9
M1
M10
M2
M3
M4
M5
M6
M7
M8
M9
N1
N10
N2
N3
N4
N5
N6
N7
N8
N9
O1
O10
O2
O3
O4
O5
O6
O7
O8
O9
P10
P2
P4
P6
P8
R86 12
J5
SERIAL_B2_RX2
J6
J7
I7
I6
J13
A1
J1
PCIE_T2B_B2_RX_DN<2>
PCIE_T2B_B2_RX_DP<4>
PCIE_T2B_B2_RX_DP<0>
PCIE_T2B_B2_RX_DN<0>
PCIE_T2B_B2_RX_DN<10>
PCIE_B2T_B2_TX_DP<9>
PCIE_B2T_B2_TX_DN<15>
PCIE_B2T_B2_TX_DP<14>
PCIE_B2T_B2_TX_DN<8>
PCIE_B2T_B2_TX_DN<10>
PCIE_B2T_B2_TX_DN<12>
PCIE_B2T_B2_TX_DN<14>
PCIE_B2T_B2_TX_DP<13>
PCIE_B2T_B2_TX_DP<15>
PCIE_B2T_B2_TX_DN<4>
PCIE_B2T_B2_TX_DN<6>
CLK_100M_B2_N<3>
PCIE_B2T_B2_TX_DP<0>
PCIE_B2T_B2_TX_DN<1>
PCIE_B2T_B2_TX_DP<2>
PCIE_B2T_B2_TX_DN<3>
PCIE_B2T_B2_TX_DP<4>
PCIE_B2T_B2_TX_DN<5>
PCIE_B2T_B2_TX_DP<6>
PCIE_B2T_B2_TX_DN<7>
CLK_100M_B2_P<3>
PCIE_B2T_B2_TX_DP<1>
PCIE_B2T_B2_TX_DP<3>
PCIE_B2T_B2_TX_DP<5>
PCIE_B2T_B2_TX_DP<7>
I10
CLK_100M_B2_P<0>
PCIE_T2B_B2_RX_DP<1>
10A5 
10A5 
10A5 
10B4 
10B4 6D5 
P12V_MEZZ_B2
CONN
C10
D1
D2
L8 PCIE_B2T_B2_TX_DN<0>
PCIE_B2T_B2_TX_DN<2>
K8
B10
B9
B8
A10
PCIE_T2B_B2_RX_DP<3>
PCIE_T2B_B2_RX_DP<5>
PCIE_T2B_B2_RX_DP<7>
PCIE_T2B_B2_RX_DN<1>
PCIE_T2B_B2_RX_DP<15>
PCIE_T2B_B2_RX_DP<13>
PCIE_T2B_B2_RX_DN<13>
PCIE_T2B_B2_RX_DN<11>
PCIE_T2B_B2_RX_DN<9>
3A
10%25 V 25 V10%
1 UF
1
402
1
402
2
C16
10%
0.1 UF
X5R25 V
2
C15
25 VX5R
0.1 UF10%
10B4 
8 7 6 5 4 3 2 1
D
C
B
A
DATE:
OFREVISION:DRAWING NUMBER:
12345678
A
B
C
D
PAGE:
AIRMAX24P
4F
4E
4D
4C
4B
4A
3F
3E
3D
3C
3B
3A
2F
2E
2D
2C
2B
2A
1F
1E
1D
1C
1B
1A
8X20RCPT
159
135
143
151
127
119
95
103
111
87
79
71
55
63
47
39
31
15
23
7
160
136
144
152
128
120
112
104
96
80
88
72
64
56
40
48
32
24
16
8
OUT
IN
BI
BI
OUT
AIRMAX155
P8
P6
P10
P4
P2
H10
H9
G10
G9
F10
F9
E10
E9
D10
D9
C10
C9
B10
B9
H8
H7
H6
H5
H4
H3
H2
H1
G8
G7
G6
G5
G4
G3
G2
G1
F8
F7
F6
F5
F4
F3
F2
F1
E8
E7
E6
E5
E4
E3
E2
E1
D8
D7
D6
D5
D4
D3
D2
D1
C8
C7
C6
C5
C4
C3
C2
C1
B8
B7
B6
B5
B4
B3
B2
B1
A3
A2
A1
A9
A8
A7
A6
A5
A4
A10
I1
I3
I2
I4
I5
I6
I7
I8
I9
I10
J1
J2
J3
J4
J5
J6
J8
J7
J10
J9
K1
K2
K3
K4
K5
K7
K6
K8
K9
K10
L1
L2
L3
L4
L5
L6
L7
L9
L8
L10
M1
M2
M3
M4
M5
M6
M8
M7
M9
M10
N1
N2
N3
N5
N4
N6
N7
N8
N10
N9
O2
O1
O3
O4
O5
O6
O7
O9
O8
O10
8X20RCPT
153
145
129
137
113
121
105
97
89
81
73
65
49
57
41
33
25
9
17
1
154
146
130
138
114
122
106
98
90
74
82
66
58
50
34
42
26
18
10
2
8X20RCPT
27
155
147
131
139
115
123
107
99
91
83
75
67
51
59
43
35
11
19
3
156
148
132
140
116
124
108
100
92
76
84
68
60
52
36
44
28
20
12
4
8X20RCPT
157
149
133
141
117
125
109
101
93
85
77
69
53
61
45
37
29
13
21
5
158
150
134
142
118
126
110
102
94
78
86
70
62
54
38
46
30
22
14
6
SEAF CONNECTOR
AIRMAX POWER CONNECTOR
AIRMAX VS2 5X10
113
CLOUD SERVER INFRASTRUCTURE ENGINEERING
 
11/24/2014
-13/11
VOLTAGE=0
P12V
TH
X7R603X7R
1 UF
603
TH
X886847-001
100 OHM CH1%603
CONN
X863844-001
3 of 4
X886612-001
SM
CONN
P12V_MEZZ_B2
4 of 4
X886612-001
SM
CONN
X886612-001
SM
CONN
1 of 4
P12V_MEZZ_B2
X886612-001
SM
CONN
2 of 4
P12V_MEZZ_B2
VOLTAGE=12
P12V_MEZZ_B2
CONN
10%25 V 25 V 10%1 UF
402402
10%
0.1 UF
X5R25 V25 VX5R
0.1 UF10%
C14
J14
C13
J16
J14
J14
J14
R86
J13
C16C15
10A5 
10A5 
10A5 
10B4 
10B4 6D5 
10B4 
BLADE_MATED_B2_N<0>
PCIE_RESET_B2_N<0>
MEZZ_B2_SDA
NC
PCIE_WAKE_B2_N
PCIE_CFG_B2_ID1
PCIE_RESET_B2_N<1>
USB_B2_P
USB_B2_N
P5V_USB_B2
CLK_100M_B2_P<2>
PCIE_T2B_B2_RX_DN<7>
PCIE_B2T_B2_TX_DN<13>
PCIE_B2T_B2_TX_DP<11>
PCIE_B2T_B2_TX_DN<9>
PCIE_B2T_B2_TX_DP<8>
BLADE_MATED_B2_N<0>
CLK_100M_B2_N<0>
PCIE_B2T_B2_TX_DN<11>
PCIE_T2B_B2_RX_DP<6>
PCIE_B2T_B2_TX_DP<10>
PCIE_B2T_B2_TX_DP<12>
PCIE_T2B_B2_RX_DN<5>
PCIE_T2B_B2_RX_DP<4>
PCIE_T2B_B2_RX_DN<3>
PCIE_T2B_B2_RX_DP<2>
PCIE_T2B_B2_RX_DN<1>
PCIE_T2B_B2_RX_DP<0>
PCIE_T2B_B2_RX_DN<6>
PCIE_T2B_B2_RX_DN<4>
PCIE_T2B_B2_RX_DN<2>
PCIE_T2B_B2_RX_DN<0>
PCIE_T2B_B2_RX_DP<15>
PCIE_T2B_B2_RX_DP<13>
PCIE_T2B_B2_RX_DP<11>
PCIE_T2B_B2_RX_DP<9>
CLK_100M_B2_P<1>
PCIE_T2B_B2_RX_DN<15>
PCIE_T2B_B2_RX_DP<14>
PCIE_T2B_B2_RX_DN<13>
PCIE_T2B_B2_RX_DP<12>
PCIE_T2B_B2_RX_DN<11>
PCIE_T2B_B2_RX_DP<10>
PCIE_T2B_B2_RX_DN<9>
PCIE_T2B_B2_RX_DP<8>
CLK_100M_B2_N<1>
PCIE_T2B_B2_RX_DN<14>
PCIE_T2B_B2_RX_DN<12>
PCIE_T2B_B2_RX_DN<10>
PCIE_T2B_B2_RX_DN<8>
PCIE_RESET_B2_N<2>
MEZZ_B2_EN
MEZZ_PRESENT_B2_N
PCIE_RESET_B2_N<3>
PCIE_CFG_B2_ID0
MEZZ_B2_SCL
CLK_100M_B2_N<2>
SERIAL_B2_TX2
PCIE_B2T_B2_TX_DP<7>
PCIE_B2T_B2_TX_DN<7>
PCIE_B2T_B2_TX_DN<5>
PCIE_B2T_B2_TX_DP<5>
PCIE_B2T_B2_TX_DP<3>
PCIE_B2T_B2_TX_DN<3>
PCIE_B2T_B2_TX_DP<1>
PCIE_B2T_B2_TX_DN<1>
CLK_100M_B2_N<2>
CLK_100M_B2_P<2>
PCIE_RESET_B2_N<0>
MEZZ_B2_SDA
PCIE_B2T_B2_TX_DP<6>
PCIE_B2T_B2_TX_DN<6>
PCIE_B2T_B2_TX_DN<4>
PCIE_B2T_B2_TX_DP<4>
PCIE_B2T_B2_TX_DP<2>
PCIE_B2T_B2_TX_DN<2>
PCIE_B2T_B2_TX_DN<0>
PCIE_B2T_B2_TX_DP<0>
PCIE_CFG_B2_ID0
MEZZ_B2_EN
PCIE_B2T_B2_TX_DP<15>
PCIE_B2T_B2_TX_DN<15>
PCIE_B2T_B2_TX_DN<13>
PCIE_B2T_B2_TX_DP<13>
PCIE_B2T_B2_TX_DP<11>
PCIE_B2T_B2_TX_DN<11>
PCIE_B2T_B2_TX_DP<9>
PCIE_B2T_B2_TX_DN<9>
PCIE_RESET_B2_N<3>
CLK_100M_B2_N<3>
CLK_100M_B2_P<3>
MEZZ_PRESENT_B2_N
PCIE_B2T_B2_TX_DP<14>
PCIE_B2T_B2_TX_DN<14>
PCIE_B2T_B2_TX_DN<12>
PCIE_B2T_B2_TX_DP<12>
PCIE_B2T_B2_TX_DP<10>
PCIE_B2T_B2_TX_DN<10>
PCIE_B2T_B2_TX_DP<8>
PCIE_B2T_B2_TX_DN<8>
PCIE_RESET_B2_N<1>
PCIE_RESET_B2_N<2>
PCIE_WAKE_B2_N
PCIE_T2B_B2_RX_DP<7>
PCIE_T2B_B2_RX_DN<7>
PCIE_T2B_B2_RX_DN<5>
PCIE_T2B_B2_RX_DP<5>
PCIE_T2B_B2_RX_DP<3>
PCIE_T2B_B2_RX_DN<3>
PCIE_T2B_B2_RX_DP<1>
CLK_100M_B2_N<0>
CLK_100M_B2_P<0>
PCIE_T2B_B2_RX_DP<6>
PCIE_T2B_B2_RX_DN<6>
PCIE_T2B_B2_RX_DN<4>
PCIE_T2B_B2_RX_DP<2>
PCIE_T2B_B2_RX_DN<15>
PCIE_T2B_B2_RX_DP<11>
PCIE_T2B_B2_RX_DP<9>
CLK_100M_B2_N<1>
CLK_100M_B2_P<1>
PCIE_CFG_B2_ID1
MEZZ_B2_SCL
PCIE_T2B_B2_RX_DP<14>
PCIE_T2B_B2_RX_DN<12>
PCIE_T2B_B2_RX_DP<12>
PCIE_T2B_B2_RX_DP<10>
PCIE_T2B_B2_RX_DN<8>
PCIE_T2B_B2_RX_DP<8>
PCIE_T2B_B2_RX_DN<14>
PSU_B2_ALERT_N
SERIAL_B2_RX2
PCIE_T2B_B2_RX_DN<2>
PCIE_T2B_B2_RX_DP<4>
PCIE_T2B_B2_RX_DP<0>
PCIE_T2B_B2_RX_DN<0>
PCIE_T2B_B2_RX_DN<10>
PCIE_B2T_B2_TX_DP<9>
PCIE_B2T_B2_TX_DN<15>
PCIE_B2T_B2_TX_DP<14>
PCIE_B2T_B2_TX_DN<8>
PCIE_B2T_B2_TX_DN<10>
PCIE_B2T_B2_TX_DN<12>
PCIE_B2T_B2_TX_DN<14>
PCIE_B2T_B2_TX_DP<13>
PCIE_B2T_B2_TX_DP<15>
PCIE_B2T_B2_TX_DN<4>
PCIE_B2T_B2_TX_DN<6>
CLK_100M_B2_N<3>
PCIE_B2T_B2_TX_DP<0>
PCIE_B2T_B2_TX_DN<1>
PCIE_B2T_B2_TX_DP<2>
PCIE_B2T_B2_TX_DN<3>
PCIE_B2T_B2_TX_DP<4>
PCIE_B2T_B2_TX_DN<5>
PCIE_B2T_B2_TX_DP<6>
PCIE_B2T_B2_TX_DN<7>
CLK_100M_B2_P<3>
PCIE_B2T_B2_TX_DP<1>
PCIE_B2T_B2_TX_DP<3>
PCIE_B2T_B2_TX_DP<5>
PCIE_B2T_B2_TX_DP<7>
CLK_100M_B2_P<0>
PCIE_T2B_B2_RX_DP<1>
PCIE_B2T_B2_TX_DN<0>
PCIE_B2T_B2_TX_DN<2>
PCIE_T2B_B2_RX_DP<3>
PCIE_T2B_B2_RX_DP<5>
PCIE_T2B_B2_RX_DP<7>
PCIE_T2B_B2_RX_DN<1>
PCIE_T2B_B2_RX_DP<15>
PCIE_T2B_B2_RX_DP<13>
PCIE_T2B_B2_RX_DN<13>
PCIE_T2B_B2_RX_DN<11>
PCIE_T2B_B2_RX_DN<9>
2
103 104
111 112
119 120
127 128
135 136
143 144
15
151 152
159
16
160
23 24
31 32
39 40
47 48
55 56
63 64
7
71 72
79
8
80
87 88
95 96
1
2
1A
1B
1C
1D
1E
1F
2A
2B
2C
2D
2E
2F
3B
3C
3D
3E
3F
4A
4B
4C
4D
4E
4F
101 102
109 110
117 118
125 126
13
133 134
14
141 142
149 150
157 158
21 22
29 30
37 38
45 46
5
53 54
6
61 62
69 70
77 78
85 86
93 94
1
100
107 108
11
115 116
12
123 124
131 132
139 140
147 148
155 156
19 20
27 28
3
35 36
4
43 44
51 52
59 60
67 68
75 76
83 84
91 92
99
1
10
105 106
113 114
121 122
129 130
137 138
145 146
153 154
17 18
2
25 26
33 34
41 42
49 50
57 58
65 66
73 74
81 82
89
9
90
97 98
A2
A3
A4
A5
A6
A7
A8
A9
B1
B2
B3
B4
B5
B6
B7
C1
C2
C3
C4
C5
C6
C7
C8
C9
D10
D3
D4
D5
D6
D7
D8
D9
E1
E10
E2
E3
E4
E5
E6
E7
E8
E9
F1
F10
F2
F3
F4
F5
F6
F7
F8
F9
G1
G10
G2
G3
G4
G5
G6
G7
G8
G9
H1
H10
H2
H3
H4
H5
H6
H7
H8
H9
I1
I2
I3
I4
I5
I8
I9
J10
J2
J3
J4
J8
J9
K1
K10
K2
K3
K4
K5
K6
K7
K9
L1
L10
L2
L3
L4
L5
L6
L7
L9
M1
M10
M2
M3
M4
M5
M6
M7
M8
M9
N1
N10
N2
N3
N4
N5
N6
N7
N8
N9
O1
O10
O2
O3
O4
O5
O6
O7
O8
O9
P10
P2
P4
P6
P8
12
J5
J6
J7
I7
I6
A1
J1
I10
C10
D1
D2
L8
K8
B10
B9
B8
A10
3A
11
22
AIRMAX24P
4F
4E
4D
4C
4B
4A
3F
3E
3D
3C
3B
3A
2F
2E
2D
2C
2B
2A
1F
1E
1D
1C
1B
1A
8X20RCPT
159
135
143
151
127
119
95
103
111
87
79
71
55
63
47
39
31
15
23
7
160
136
144
152
128
120
112
104
96
80
88
72
64
56
40
48
32
24
16
8
OUT
IN
BI
BI
OUT
AIRMAX155
P8
P6
P10
P4
P2
H10
H9
G10
G9
F10
F9
E10
E9
D10
D9
C10
C9
B10
B9
H8
H7
H6
H5
H4
H3
H2
H1
G8
G7
G6
G5
G4
G3
G2
G1
F8
F7
F6
F5
F4
F3
F2
F1
E8
E7
E6
E5
E4
E3
E2
E1
D8
D7
D6
D5
D4
D3
D2
D1
C8
C7
C6
C5
C4
C3
C2
C1
B8
B7
B6
B5
B4
B3
B2
B1
A3
A2
A1
A9
A8
A7
A6
A5
A4
A10
I1
I3
I2
I4
I5
I6
I7
I8
I9
I10
J1
J2
J3
J4
J5
J6
J8
J7
J10
J9
K1
K2
K3
K4
K5
K7
K6
K8
K9
K10
L1
L2
L3
L4
L5
L6
L7
L9
L8
L10
M1
M2
M3
M4
M5
M6
M8
M7
M9
M10
N1
N2
N3
N5
N4
N6
N7
N8
N10
N9
O2
O1
O3
O4
O5
O6
O7
O9
O8
O10
8X20RCPT
153
145
129
137
113
121
105
97
89
81
73
65
49
57
41
33
25
9
17
1
154
146
130
138
114
122
106
98
90
74
82
66
58
50
34
42
26
18
10
2
8X20RCPT
27
155
147
131
139
115
123
107
99
91
83
75
67
51
59
43
35
11
19
3
156
148
132
140
116
124
108
100
92
76
84
68
60
52
36
44
28
20
12
4
8X20RCPT
157
149
133
141
117
125
109
101
93
85
77
69
53
61
45
37
29
13
21
5
158
150
134
142
118
126
110
102
94
78
86
70
62
54
38
46
30
22
14
6
8 7 6 5 4 3 2 1
D
C
B
A
DATE:
OFREVISION:DRAWING NUMBER:
12345678
A
B
C
D
PAGE:



EVT,PVT0     0     0
SKU ID BITS SFP+ VCC FILTERSBLADE ENABLE TEST HEADER
PSU ALERT TEST HEADER
ETHERNET AIRMAX 3X6 CONNECTOR
1     0     0
0     1     1
10GB SFP+ CONNECTOR
SFP+ MISC PU/PD
0     1     0
0     0     1
SKU2  SKU1  SKU0
114
CLOUD SERVER INFRASTRUCTURE ENGINEERING
 
11/24/2014
-14/11
P3V3_B1_QSFP
BOM_IGNORE
10 KOHM
R6
1
R4
10 KOHM
CH603
100 OHM
R12
DP_ETH40G_B1_TX0
2
ETH10G_B1_TX_FAULT
ETH40G_B1_TX3N
ETH40G_B1_RX3P
ETH40G_B1_RX2N
ETH40G_B1_TX2P
ETH40G_B1_RX1N
ETH40G_B1_TX1P
ETH40G_B1_RX3N
DP_ETH10G_B1_RX
DP_ETH10G_B1_RX
J6
J4
J2
I6
I5
I4
I3
I2
I1
H6
H5
H4
H3
H2
H1
G6
G5
G4
G3
G2
G1
F6
F5
F4
F3
F2
F1
E6
E5
E4
E3
E2
E1
D6
D5
D4
D3
D2
D1
C6
C5
C4
C3
C2
C1
B6
B5
B4
B3
B2
B1
A6
A5
A4
A3
A2
A1
J7
1
9
8
7
6
5
4
3
20
2
19
18
17
16
15
14
13
12
11
10
1
J6
20
17
1
14
11
10
16
15
2
3
18
19
4
5
8
9
7
13
12
6
J5
2
1
R28
2
1
R26
2
1
R3
2
1
R5
2
1
R7
2
1
22
1
R2
2
1
R18
1
R20
2
1
R22
2
1
R24
2
1
R27
2
1
R29
2
1
2
1
R23
2
1
R25
PSU_B1_ALERT_N
ETH40G_B1_TX0P
BLADE_B1_MATED_N<1>
ETH40G_B1_TX0N
TH
DP_ETH40G_B1_RX3
CH
1%
ETH40G_B1_SCL
ETH40G_B1_RX2P
SKU_B1_ID2
SERIAL_B1_RX2
SERIAL_B1_TX1
SERIAL_B1_TX2
SERIAL_B1_RX1
BLADE_B1_EN1
ETH40G_B1_RX0N
ETH40G_B1_PRES_N
DP_ETH10G_B1_TX2
ETH10G_B1_TXN
CONN
NC
ETH10G_B1_RXN
ETH40G_B1_SDA
ETH10G_B1_SCL
ETH10G_B1_SDA
DP_ETH10G_B1_TX2
ETH40G_B1_TX2N
ETH40G_B1_TX1N
DP_ETH40G_B1_TX2
DP_ETH40G_B1_TX3
DP_ETH40G_B1_RX2
DP_ETH40G_B1_TX3
DP_ETH40G_B1_RX1
DP_ETH40G_B1_RX3
DP_ETH40G_B1_RX2
DP_ETH40G_B1_TX2
DP_ETH40G_B1_RX1
DP_ETH40G_B1_TX1
DP_ETH40G_B1_TX1
DP_ETH40G_B1_RX0
ETH40G_B1_RX0P
ETH40G_B1_RX1P
ETH40G_B1_TX3P
ETH10G_B1_RXP
SKU_B1_ID1
SFP_RCPT_20P
X881930-001
ETH10G_B1_TXN
ETH10G_B1_TXP
P3V3_10G_B1_VCCT
P3V3_10G_B1_VCCR
CH603
1%
CH603
BOM_IGNORE
X881931-001
ETH10G_B1_RXN
ETH10G_B1_RXP
SKU_B1_ID0
SKU_B1_ID1
SKU_B1_ID2
603CH
1%100 OHM
603CH
1%BOM_IGNORE
603CH
1%10 KOHM
1%
CH
1%
BOM_IGNORE
603CH
1%10 KOHM
BOM_IGNORE
603
CH
1%10 KOHM
ETH10G_B1_SDA
ETH10G_B1_SCL
P3V3_B1_QSFP
603CH
1%10 KOHM10 KOHM1%
CH603
BOM_IGNORE
603CH
1%100 OHM
10 KOHM
CH603
10 KOHM
1%
603CH
1%
P3V3_B1_QSFP
10 KOHM1%
100 OHM
1%
CH
1%
CH603
CONN
SFP_HSNG_20P
SM
CONN
ETH10G_B1_SDA
TH
ETH10G_B1_TXP
SKU_B1_ID0
1%
CH603
100 OHM
603
100 OHM
BOM_IGNORE
DP_ETH40G_B1_TX0
DP_ETH40G_B1_RX0
P3V3_B1_QSFP
10 KOHM
6032
ETH10G_B1_MOD_ABS
21 R15
0 OHM603 5%CH
ETH10G_B1_PRES_N
ETH10G_B1_MOD_ABS
ETH10G_B1_RX_LOS
ETH10G_B1_TX_DIS
ETH10G_B1_RS0
ETH10G_B1_RS1
ETH10G_B1_RX_LOS
BOM_IGNORE
603
100 OHM
R21
ETH10G_B1_TX_FAULT
P3V3_B1_QSFP
5D6 
5C3 
5C6 
5D3 
5C3 
5D6 
5C3 
10B7 
5D3 
5C6 
10B7 2D6 
10B7 
10B7 
10B7 8C7 
10B7 
5C6 
5C2 
5D3 
5D6 
5C6 
5C3 
5D6 
ETH10G_B1_TX_DIS
ETH10G_B1_SCL
ETH10G_B1_RS0
ETH10G_B1_RS1
X881927-001
BOM_IGNORE
2
1
J25
SM
2
1
J26
BOM_IGNORE
SM
BLADE_B1_EN1
PSU_B1_ALERT_N
1%603
1 2
CH100 OHM
BOM_IGNORE
R9
603 1%
BOM_IGNORE
1 2
CH100 OHM
R11
P3V3_B1_QSFP
2
5%100 PF
NPO50 V
402
C81
402
10%0.1 UF
X5R25 V
C71
2
BOM_IGNORE
FB30 OHM
2.2 A 402
0.035DCR
FB1
1 2
X812373-001
EMPTY
402
BOM_IGNORE
FS21 2
5%CH6030 OHM
R171 2
BOM_IGNORE
2.2 A
FB
0.035DCR
30 OHM
402
FB2
1 2
10%
402X5R25 V
0.1 UFC6 1
2
CH603 5%
R131 2
0 OHM
402
X812373-001
1 2
BOM_IGNORE
EMPTY
FS1
P3V3_B1_QSFP
100 PF
50 VNPO402
5%
C5 1
2
P3V3_10G_B1_VCCR
P3V3_10G_B1_VCCT
VOLTAGE=3.3
VOLTAGE=3.3
10B7 
10B7 
8 7 6 5 4 3 2 1
D
C
B
A
DATE:
OFREVISION:DRAWING NUMBER:
12345678
A
B
C
D
PAGE:
1X2HDR
1X2HDR
IN
OUT
OUT
OUT
IN
OUT
IN
IN
IN
IN
OUT
RCPT
AIRMAX57P
J6
J4
J2
I6
I5
I4
I3
I2
I1
H6
H5
H4
H3
H2
H1
G6
G5
G4
G3
G2
G1
F6
F5
F4
F3
F2
F1
E6
E5
E4
E3
E2
E1
D6
D5
D4
D3
D2
D1
C6
C5
C4
C3
C2
C1
B6
B5
B4
B3
B2
B1
A6
A5
A4
A3
A2
A1
OUT
IN
IN
IN
OUT
OUT
IN
IN
IN
OUT
IN
GND20
GND19
GND18
GND17
GND16
GND15
GND14
GND13
GND12
GND11
GND10
GND9
GND8
GND7
GND6
GND5
GND4
GND3
GND2
GND1
VEET3
TD_N
TD_P
VEET2
VCCT
VCCR
VEER3
RD_P
RD_N
VEER2
VEER1
RS1
RX_ LOS
RS0
MOD_ABS
SCL
SDA
TX_DISABLE
TX_FAULT
VEET1
EVT,PVT0     0     0
SKU ID BITS SFP+ VCC FILTERSBLADE ENABLE TEST HEADER
PSU ALERT TEST HEADER
ETHERNET AIRMAX 3X6 CONNECTOR
1     0     0
0     1     1
10GB SFP+ CONNECTOR
SFP+ MISC PU/PD
0     1     0
0     0     1
SKU2  SKU1  SKU0
DP_ETH40G_B1_TX0
DP_ETH10G_B1_RX
DP_ETH10G_B1_RX
DP_ETH40G_B1_RX3
DP_ETH10G_B1_TX2
DP_ETH10G_B1_TX2
DP_ETH40G_B1_TX2
DP_ETH40G_B1_TX3
DP_ETH40G_B1_RX2
DP_ETH40G_B1_TX3
DP_ETH40G_B1_RX1
DP_ETH40G_B1_RX3
DP_ETH40G_B1_RX2
DP_ETH40G_B1_TX2
DP_ETH40G_B1_RX1
DP_ETH40G_B1_TX1
DP_ETH40G_B1_TX1
DP_ETH40G_B1_RX0
DP_ETH40G_B1_TX0
DP_ETH40G_B1_RX0
114
CLOUD SERVER INFRASTRUCTURE ENGINEERING
 
11/24/2014
-14/11
P3V3_B1_QSFP
BOM_IGNORE
10 KOHM10 KOHM
CH603
100 OHM
TH
CH
1%
CONN
SFP_RCPT_20P
X881930-001
CH
603
1%
CH603
BOM_IGNORE
X881931-001
603CH
1%100 OHM
603CH
1%BOM_IGNORE
603CH
1%10 KOHM
1%
CH
1%
BOM_IGNORE
603CH
1%10 KOHM
BOM_IGNORE
603
CH
1%10 KOHM
P3V3_B1_QSFP
603
CH
1%10 KOHM10 KOHM1%
CH603
BOM_IGNORE
603CH
1%100 OHM
10 KOHM
CH603
10 KOHM
1%
603CH
1%
P3V3_B1_QSFP
10 KOHM1%
100 OHM
1%
CH
1%
CH603
CONN
SFP_HSNG_20P
SM
CONN
TH
1%
CH603
100 OHM
603
100 OHM
BOM_IGNORE
P3V3_B1_QSFP
10 KOHM
603
0 OHM603 5%CH
BOM_IGNORE
603
100 OHM
P3V3_B1_QSFP
X881927-001
BOM_IGNORE
SM
BOM_IGNORE
SM
1%603 CH100 OHM
BOM_IGNORE
603 1%
BOM_IGNORE
CH100 OHM
P3V3_B1_QSFP
5%100 PF
NPO50 V
402402
10%0.1 UF
X5R25 V
BOM_IGNORE
FB30 OHM
2.2 A 402
0.035DCR
X812373-001
EMPTY
402
BOM_IGNORE
5%CH6030 OHM
BOM_IGNORE
2.2 A
FB
0.035DCR
30 OHM
402
10%
402X5R25 V
0.1 UF
CH603 5%0 OHM
402
X812373-001BOM_IGNORE
EMPTY
P3V3_B1_QSFP
100 PF
50 VNPO402
5%
VOLTAGE=3.3
VOLTAGE=3.3
R6R4
R12
J7
J6
J5
R28R26
R3 R5 R7
R2
R18 R20 R22 R24 R27 R29
R23 R25
R15
R21
J25
J26
R9
R11
C8C7
FB1
FS2
R17
FB2
C6
R13
FS1
C5
5D6 
5C3 
5C6 
5D3 
5C3 
5D6 
5C3 
10B7 
5D3 
5C6 
10B7 2D6 
10B7 
10B7 
10B7 8C7 
10B7 
5C6 
5C2 
5D3 
5D6 
5C6 
5C3 
5D6 
10B7 
10B7 
ETH10G_B1_TX_FAULT
ETH40G_B1_TX3N
ETH40G_B1_RX3P
ETH40G_B1_RX2N
ETH40G_B1_TX2P
ETH40G_B1_RX1N
ETH40G_B1_TX1P
ETH40G_B1_RX3N
PSU_B1_ALERT_N
ETH40G_B1_TX0P
BLADE_B1_MATED_N<1>
ETH40G_B1_TX0N
ETH40G_B1_SCL
ETH40G_B1_RX2P
SKU_B1_ID2
SERIAL_B1_RX2
SERIAL_B1_TX1
SERIAL_B1_TX2
SERIAL_B1_RX1
BLADE_B1_EN1
ETH40G_B1_RX0N
ETH40G_B1_PRES_N
ETH10G_B1_TXN
NC
ETH10G_B1_RXN
ETH40G_B1_SDA
ETH10G_B1_SCL
ETH10G_B1_SDA
ETH40G_B1_TX2N
ETH40G_B1_TX1N
ETH40G_B1_RX0P
ETH40G_B1_RX1P
ETH40G_B1_TX3P
ETH10G_B1_RXP
SKU_B1_ID1
ETH10G_B1_TXN
ETH10G_B1_TXP
P3V3_10G_B1_VCCT
P3V3_10G_B1_VCCR
ETH10G_B1_RXN
ETH10G_B1_RXP
SKU_B1_ID0
SKU_B1_ID1
SKU_B1_ID2
ETH10G_B1_SDA
ETH10G_B1_SCL
ETH10G_B1_SDA
ETH10G_B1_TXP
SKU_B1_ID0
ETH10G_B1_MOD_ABS
ETH10G_B1_PRES_N
ETH10G_B1_MOD_ABS
ETH10G_B1_RX_LOS
ETH10G_B1_TX_DIS
ETH10G_B1_RS0
ETH10G_B1_RS1
ETH10G_B1_RX_LOS
ETH10G_B1_TX_FAULT
ETH10G_B1_TX_DIS
ETH10G_B1_SCL
ETH10G_B1_RS0
ETH10G_B1_RS1
BLADE_B1_EN1
PSU_B1_ALERT_N
P3V3_10G_B1_VCCR
P3V3_10G_B1_VCCT
1
2
J6
J4
J2
I6
I5
I4
I3
I2
I1
H6
H5
H4
H3
H2
H1
G6
G5
G4
G3
G2
G1
F6
F5
F4
F3
F2
F1
E6
E5
E4
E3
E2
E1
D6
D5
D4
D3
D2
D1
C6
C5
C4
C3
C2
C1
B6
B5
B4
B3
B2
B1
A6
A5
A4
A3
A2
A1
1
9
8
7
6
5
4
3
20
2
19
18
17
16
15
14
13
12
11
10
1
20
17
1
14
11
10
16
15
2
3
18
19
4
5
8
9
7
13
12
6
2
1
2
1
2
1
2
1
2
1
2
1
22
1
2
1 1
2
1
2
1
2
1 2
1
2
1
2
1
2
1
2
21
2
1
2
1
1 2
1 2
2
11
21 2
1 2
1 2
1 2
1
2
1 2
1 2
1
2
1X2HDR
1X2HDR
IN
OUT
OUT
OUT
IN
OUT
IN
IN
IN
IN
OUT
RCPT
AIRMAX57P
J6
J4
J2
I6
I5
I4
I3
I2
I1
H6
H5
H4
H3
H2
H1
G6
G5
G4
G3
G2
G1
F6
F5
F4
F3
F2
F1
E6
E5
E4
E3
E2
E1
D6
D5
D4
D3
D2
D1
C6
C5
C4
C3
C2
C1
B6
B5
B4
B3
B2
B1
A6
A5
A4
A3
A2
A1
OUT
IN
IN
IN
OUT
OUT
IN
IN
IN
OUT
IN
GND20
GND19
GND18
GND17
GND16
GND15
GND14
GND13
GND12
GND11
GND10
GND9
GND8
GND7
GND6
GND5
GND4
GND3
GND2
GND1
VEET3
TD_N
TD_P
VEET2
VCCT
VCCR
VEER3
RD_P
RD_N
VEER2
VEER1
RS1
RX_ LOS
RS0
MOD_ABS
SCL
SDA
TX_DISABLE
TX_FAULT
VEET1
8 7 6 5 4 3 2 1
D
C
B
A
DATE:
OFREVISION:DRAWING NUMBER:
12345678
A
B
C
D
PAGE:



40G QSFP+ CONNECTOR
QSFP+ VCC FILTER
QSFP+ VCC TX FILTER
SKU_ID2 TIED TO QSFP+ RESETCYA IF QSFP+ REQUIRES A RESET
QSFP+ VCC RX FILTER
QSFP+ MISC PU/PD
QSFP+ HOUSING W/O HEATSINK
X89416-001
115
CLOUD SERVER INFRASTRUCTURE ENGINEERING
 
11/24/2014
-15/11
BOM_IGNORE BOM_IGNORE
R77
ETH40G_B1_MODSEL_N
ETH40G_B1_LPMODE
2
1
603
100 OHM1%
CH CH
1%100 OHM
603
R79
1
2
P3V3_B1_QSFP
1
2
20%
TH
X886611-001
SFP_HSNG_12P
CONN
SM
22
24
ETH40G_B1_TX0P4C8 
4C8 
4C8 
4D5 
4D8 
4D8 
4C5 
4C8 
4D8 
4D8 
4C8 
4D8 
4D8 
4D8 
4D8 
4C5 
1
10 KOHM 1%
BOM_IGNORE
ETH40G_B1_INT_N
ETH40G_B1_SDA
6.3 V
603
22 UF20%
X5R
C391
2
P3V3_B1_QSFP
BOM_IGNORE603CH
1%
R82
8
20%22 UF
603X5R6.3 V
C30 1
2
P3V3_40G_B1_VCC_TX
X5R6.3 V
603
22 UFC361
2
20%22 UF
603
6.3 VX5R
C351
2
P3V3_40G_B1_VCC_RX
1
EMPTY
0.035DCR
BOM_IGNORE
0.1 UF
20
ETH40G_B1_MODPRS_N
9
7
6
5
4
3
2
12
11
10
1
J9
21
R75
2FS8
21 R72
21
FB8
2
1 C31
2910
30
6
5
33
34
3
2
36
37
12
11
2514
15
21
17
18
9
8
27
31
28
38
35
327
4
1
26
23
19
16
13
J8
21 R80
2
1C29
21
FB10
21 FS10
21 R74
21 FS9 21
FB9
21 R73
2
1 C32
2
1
R83
2
1
R84
22
1
R81
2
1
R78R76
X886610-001
ETH40G_B1_TX1P
ETH40G_B1_TX1N
SFP_RCPT_38P
P3V3_40G_B1_VCC1
P3V3_40G_B1_VCC_TX
10 KOHM
603
P3V3_B1_QSFP
25 VX5R
2.2 A
0.035DCR X812373-001BOM_IGNORE
ETH40G_B1_RX0P
ETH40G_B1_RX0N
ETH40G_B1_RESET_N
ETH40G_B1_SCL
ETH40G_B1_TX3N
ETH40G_B1_TX3P
ETH40G_B1_MODSEL_N
10 KOHM1%
CH603
ETH40G_B1_TX0N
ETH40G_B1_TX2N
ETH40G_B1_TX2P
ETH40G_B1_RX3P
ETH40G_B1_RX3N
ETH40G_B1_RX1P
ETH40G_B1_RX1N
ETH40G_B1_RX2P
ETH40G_B1_RX2N
VOLTAGE=3.3
VOLTAGE=3.3
603 CHBOM_IGNORE
0 OHM 5%
SKU_B1_ID2
P3V3_B1_QSFP
P3V3_40G_B1_VCC1
ETH40G_B1_PRES_NETH40G_B1_SDA
ETH40G_B1_INT_NETH40G_B1_SCL
P3V3_40G_B1_VCC_RX
ETH40G_B1_RESET_N
ETH40G_B1_LPMODE
P3V3_B1_QSFP
10%0.1 UF
402X5R
25 V
2.2 A
FB
402
30 OHM
CH0 OHM 5%603
X812373-001
402
BOM_IGNORE
BOM_IGNORE
EMPTY
402
X812373-001
5%0 OHM CH603
BOM_IGNORE
402
0.035DCR
FB
2.2 A
30 OHM
10%
402X5R25 V
402
10%0.1 UF
BOM_IGNORE
402
30 OHM FB EMPTY
402
CH603 5%0 OHM
CONN
603CH
1%10 KOHM
603
CH
1%10 KOHM
603 CH0 OHM 5%
603
CH
10 KOHM
CH
1%
8 7 6 5 4 3 2 1
D
C
B
A
DATE:
OFREVISION:DRAWING NUMBER:
12345678
A
B
C
D
PAGE:
OUT
IN
IN
IN
IN
OUT
GND_TX_6
TX1_N
TX1_P
GND_TX_5
TX3_N
TX3_P
GND_TX_4
LPMODE
VCC1
VCC_TX
INT_N
MODPRS_N
GND_RX_6
RX4_P
RX4_N
GND_RX_5
RX2_P
RX2_N
GND_RX_4GND_RX_3
RX1_N
RX1_P
GND_RX_2
RX3_P
RX3_N
SDA
SCL
VCC_RX
RESET_N
MODSEL_N
GND_TX_3
TX4_P
TX4_N
GND_TX_2
TX2_N
TX2_P
GND_TX_1
GND_RX_1
OUT
GND1
GND2
GND3
GND4
GND5
GND6
GND7
GND8
GND9
GND10
GND11
GND12
IN
OUT
OUT
OUT
OUT
IN
IN
IN
IN
OUT
OUT
40G QSFP+ CONNECTOR
QSFP+ VCC FILTER
QSFP+ VCC TX FILTER
SKU_ID2 TIED TO QSFP+ RESETCYA IF QSFP+ REQUIRES A RESET
QSFP+ VCC RX FILTER
QSFP+ MISC PU/PD
QSFP+ HOUSING W/O HEATSINK
X89416-001
115
CLOUD SERVER INFRASTRUCTURE ENGINEERING
 
11/24/2014
-15/11
BOM_IGNORE BOM_IGNORE
603
100 OHM1%
CH CH
1%100 OHM
603
P3V3_B1_QSFP
20%
TH
X886611-001
SFP_HSNG_12P
CONN
SM
10 KOHM 1%
BOM_IGNORE
6.3 V
603
22 UF20%
X5R
P3V3_B1_QSFP
BOM_IGNORE603CH
1%
20%22 UF
603X5R6.3 V
X5R
6.3 V
603
22 UF
20%22 UF
603
6.3 VX5R
EMPTY
0.035DCR
BOM_IGNORE
0.1 UF
X886610-001
SFP_RCPT_38P
10 KOHM
603
P3V3_B1_QSFP
25 VX5R
2.2 A
0.035DCR X812373-001BOM_IGNORE
10 KOHM1%
CH603
603 CHBOM_IGNORE
0 OHM 5%P3V3_B1_QSFP
P3V3_B1_QSFP
10%0.1 UF
402X5R
25 V
2.2 A
FB
402
30 OHM
CH0 OHM 5%603
X812373-001
402
BOM_IGNORE
BOM_IGNORE
EMPTY
402
X812373-001
5%0 OHM CH603
BOM_IGNORE
402
0.035DCR
FB
2.2 A
30 OHM
10%
402X5R
25 V
402
10%0.1 UF
BOM_IGNORE
402
30 OHM FB EMPTY
402
CH603 5%0 OHM
CONN
603CH
1%10 KOHM
603
CH
1%10 KOHM
603 CH0 OHM 5%
603
CH
10 KOHM
CH
1%
VOLTAGE=3.3
VOLTAGE=3.3 R77 R79
C39
R82
C30
C36
C35
J9
R75
FS8
R72
FB8
C31
J8
R80
C29
FB10 FS10
R74
FS9 FB9
R73
C32
R83 R84R81R78R76
4C8 
4C8 
4C8 
4D5 
4D8 
4D8 
4C5 
4C8 
4D8 
4D8 
4C8 
4D8 
4D8 
4D8 
4D8 
4C5 
ETH40G_B1_MODSEL_N
ETH40G_B1_LPMODE
ETH40G_B1_TX0P
ETH40G_B1_INT_N
ETH40G_B1_SDA
P3V3_40G_B1_VCC_TX
P3V3_40G_B1_VCC_RX
ETH40G_B1_MODPRS_N
ETH40G_B1_TX1P
ETH40G_B1_TX1N
P3V3_40G_B1_VCC1
P3V3_40G_B1_VCC_TX
ETH40G_B1_RX0P
ETH40G_B1_RX0N
ETH40G_B1_RESET_N
ETH40G_B1_SCL
ETH40G_B1_TX3N
ETH40G_B1_TX3P
ETH40G_B1_MODSEL_N
ETH40G_B1_TX0N
ETH40G_B1_TX2N
ETH40G_B1_TX2P
ETH40G_B1_RX3P
ETH40G_B1_RX3N
ETH40G_B1_RX1P
ETH40G_B1_RX1N
ETH40G_B1_RX2P
ETH40G_B1_RX2N
SKU_B1_ID2
P3V3_40G_B1_VCC1
ETH40G_B1_PRES_NETH40G_B1_SDA
ETH40G_B1_INT_NETH40G_B1_SCL
P3V3_40G_B1_VCC_RX
ETH40G_B1_RESET_N
ETH40G_B1_LPMODE
2
1 1
2
1
2
22
24
1
1
2
81
2
1
2
1
21
20
9
7
6
5
4
3
2
12
11
10
1
2 1
2
21
2 1 2
1
2910
30
6
5
33
34
3
2
36
37
12
11
2514
15
21
17
18
9
8
27
31
28
38
35
327
4
1
26
23
19
16
13
21
2
1
2 1 2 1
21
2 1 2 1
21
2
1
2
1
2
1
22
1
2
1
OUT
IN
IN
IN
IN
OUT
GND_TX_6
TX1_N
TX1_P
GND_TX_5
TX3_N
TX3_P
GND_TX_4
LPMODE
VCC1
VCC_TX
INT_N
MODPRS_N
GND_RX_6
RX4_P
RX4_N
GND_RX_5
RX2_P
RX2_N
GND_RX_4GND_RX_3
RX1_N
RX1_P
GND_RX_2
RX3_P
RX3_N
SDA
SCL
VCC_RX
RESET_N
MODSEL_N
GND_TX_3
TX4_P
TX4_N
GND_TX_2
TX2_N
TX2_P
GND_TX_1
GND_RX_1
OUT
GND1
GND2
GND3
GND4
GND5
GND6
GND7
GND8
GND9
GND10
GND11
GND12
IN
OUT
OUT
OUT
OUT
IN
IN
IN
IN
OUT
OUT
8 7 6 5 4 3 2 1
D
C
B
A
DATE:
OFREVISION:DRAWING NUMBER:
12345678
A
B
C
D
PAGE:



0     0     1
1     0     0
0     1     1
0     1     0
0     0     0 EVT,PVT
SKU ID BITS
SKU2  SKU1  SKU0
SFP+ VCC FILTERS
PSU ALERT TEST HEADER
SFP+ MISC PU/PD
BLADE ENABLE TEST HEADER
10GB SFP+ CONNECTOR
ETHERNET AIRMAX 3X6 CONNECTOR
116
CLOUD SERVER INFRASTRUCTURE ENGINEERING
 
11/24/2014
-16/11
SKU_B2_ID0
SKU_B2_ID1
SKU_B2_ID2
2
1
R31
100 OHM
603CH
1%
2
1
R33
603CH
1%100 OHM
2
1
R30
10 KOHM
603
BOM_IGNORE
CH
1%
2
1
R32
BOM_IGNORE
603CH
1%10 KOHM
P3V3_B2_QSFP
2
R35
100 OHM1%
CH603
1
2
1
R34
BOM_IGNORE
603CH
1%10 KOHM
PSU_B2_ALERT_N
SM
2
1
J29
BOM_IGNORE 100 OHM603 1%CH
BOM_IGNORE
R391 2
BLADE_B2_EN1
100 OHM603
BOM_IGNORE
1
J28
DP_ETH40G_B2_TX3
DP_ETH40G_B2_RX3
B5
H2
ETH40G_B2_PRES_N
ETH40G_B2_TX0P
F3
ETH10G_B2_TXP
ETH40G_B2_RX0N
DP_ETH40G_B2_RX0
DP_ETH10G_B2_TX2
C5
ETH10G_B2_RXN
ETH10G_B2_SDA
DP_ETH10G_B2_RX
DP_ETH40G_B2_RX0
J4
DP_ETH40G_B2_TX0
CONN P3V3_B2_QSFP
SKU_B2_ID2
BLADE_B2_EN1
E1
I2
P3V3_B2_QSFP
F4
SM
2
1
BOM_IGNORE
FB3
2
VOLTAGE=3.3
X812373-001BOM_IGNORE
10 KOHM
1
ETH10G_B2_SCL
ETH10G_B2_SDA
ETH10G_B2_TX_DIS
ETH10G_B2_TX_FAULT
ETH10G_B2_TXN
ETH10G_B2_TXP
ETH10G_B2_RXN
ETH10G_B2_RXP
P3V3_10G_B2_VCCR
P3V3_10G_B2_VCCT
100 PF
50 VNPO402
5%
402
EMPTY
6030 OHM 5%
10%
402X5R25 V
0.1 UF
BOM_IGNORE
2.2 A
FB
0.035DCR
30 OHM
402
5%CH6030 OHM
X812373-001
EMPTY
402
BOM_IGNORE
FB30 OHM
2.2 A 402
0.035DCR
BOM_IGNORE
402
10%0.1 UF
X5R25 V 5%100 PF
NPO50 V
402
603CH
1%10 KOHM
BOM_IGNORE
100 OHM1%
CH603
1%
CH603
BOM_IGNORE
603CH
1%100 OHM
603
CH
1%10 KOHM
603
CH
1%10 KOHM
100 OHM1%
CH603
BOM_IGNORE
603CH
1%10 KOHM 10 KOHM1%
CH603
10 KOHM
1%
CH603
BOM_IGNORE
10 KOHM
1%
CH603
BOM_IGNORE
ETH10G_B2_SDA
ETH10G_B2_SCL
P3V3_B2_QSFP
ETH10G_B2_TX_FAULT
ETH10G_B2_TX_DIS
ETH10G_B2_RS0
P3V3_B2_QSFP
ETH10G_B2_RS1
P3V3_10G_B2_VCCR
P3V3_B2_QSFP
P3V3_10G_B2_VCCT
CONN
SFP_RCPT_20P
SFP_HSNG_20P
CONN
TH
X881931-001
ETH10G_B2_RS1
VOLTAGE=3.3
P3V3_B2_QSFP
TH
X881927-001
603CH
1%100 OHM
ETH10G_B2_RXP
ETH40G_B2_TX3P
ETH40G_B2_RX1P
ETH40G_B2_RX2P
ETH40G_B2_TX3N
ETH40G_B2_RX3P
ETH40G_B2_TX2P
ETH40G_B2_TX1P
ETH40G_B2_TX2N
ETH40G_B2_TX1N
ETH40G_B2_RX2N
ETH40G_B2_RX1N
ETH40G_B2_RX3N
DP_ETH10G_B2_RX
DP_ETH40G_B2_RX3
DP_ETH40G_B2_RX1
DP_ETH40G_B2_RX2
DP_ETH40G_B2_TX1
DP_ETH40G_B2_TX2
DP_ETH40G_B2_TX1
DP_ETH40G_B2_TX2
DP_ETH40G_B2_RX2
DP_ETH40G_B2_RX1
DP_ETH40G_B2_TX3
ETH10G_B2_TXN
SERIAL_B2_TX2
ETH10G_B2_RS0
ETH10G_B2_RX_LOS
ETH10G_B2_MOD_ABS
CH
SKU_B2_ID1
DP_ETH40G_B2_TX0
DP_ETH10G_B2_TX2
SERIAL_B2_RX1
SERIAL_B2_RX2
PSU_B2_ALERT_N
R56
1
2
R54
1
2
R57
1
2
R55
1
2
R53
1
2
R52
1
2
R50
2
R51
1
2
R48
1
2
R49
1
2
J17
6
12
13
7
9
8
5
4
19
18
3
2
15
16
10
11
14
1
17
20
J18
1
10
11
12
13
14
15
16
17
18
19
2
20
3
4
5
6
7
8
9
R46
1
2
C121
2
C111
21
FS41 2
R451 2
FB4
1 2
C10 1
2
R40
2
R411 2
FS31 2
C9 1
2
J19
A1
A2
A3
A4
A5
A6
B1
B2
B3
B4
B6
C1
C2
C3
C4
C6
D1
D2
D3
D4
D5
D6
E3
E4
E5
E6
F1
F2
F5
F6
G1
G2
G4
G5
G6
H1
H3
H4
H5
H6
I1
I3
I4
I5
I6
J2
J6
ETH10G_B2_RX_LOS
21 R43
5%
ETH10G_B2_MOD_ABS
E2
X881930-001
SM
SERIAL_B2_TX1
G3
0 OHM603 CH
SKU_B2_ID0
ETH40G_B2_SCL
7C2 
7C6 
10B4 
7D6 
7C3 
7C6 
7D6 
7C3 
7D3 
7D6 
7D3 
7D6 
7C6 
7C3 
7C3 
7C6 
10B4 9C7 
10B4 3D6 
10B4 
10B4 
7D3 
10B4 
ETH10G_B2_PRES_N
BLADE_B2_MATED_N<2>
ETH40G_B2_TX0N
1
2
1%CH
R37
ETH10G_B2_SCL
ETH40G_B2_SDA
ETH40G_B2_RX0P
10B4 
10B4 
8 7 6 5 4 3 2 1
D
C
B
A
DATE:
OFREVISION:DRAWING NUMBER:
12345678
A
B
C
D
PAGE:
IN
OUT
OUT
OUT
OUT
OUT
OUT
OUT
IN
IN
IN
IN
IN
IN
IN
IN
RCPT
AIRMAX57P
J6
J4
J2
I6
I5
I4
I3
I2
I1
H6
H5
H4
H3
H2
H1
G6
G5
G4
G3
G2
G1
F6
F5
F4
F3
F2
F1
E6
E5
E4
E3
E2
E1
D6
D5
D4
D3
D2
D1
C6
C5
C4
C3
C2
C1
B6
B5
B4
B3
B2
B1
A6
A5
A4
A3
A2
A1
1X2HDR
1X2HDR
IN
IN
IN
OUT
IN
OUT
GND20
GND19
GND18
GND17
GND16
GND15
GND14
GND13
GND12
GND11
GND10
GND9
GND8
GND7
GND6
GND5
GND4
GND3
GND2
GND1
VEET3
TD_N
TD_P
VEET2
VCCT
VCCR
VEER3
RD_P
RD_N
VEER2
VEER1
RS1
RX_ LOS
RS0
MOD_ABS
SCL
SDA
TX_DISABLE
TX_FAULT
VEET1
0     0     1
1     0     0
0     1     1
0     1     0
0     0     0 EVT,PVT
SKU ID BITS
SKU2  SKU1  SKU0
SFP+ VCC FILTERS
PSU ALERT TEST HEADER
SFP+ MISC PU/PD
BLADE ENABLE TEST HEADER
10GB SFP+ CONNECTOR
ETHERNET AIRMAX 3X6 CONNECTOR
DP_ETH40G_B2_TX3
DP_ETH40G_B2_RX3
DP_ETH40G_B2_RX0
DP_ETH10G_B2_TX2
DP_ETH10G_B2_RX
DP_ETH40G_B2_RX0
DP_ETH40G_B2_TX0
DP_ETH10G_B2_RX
DP_ETH40G_B2_RX3
DP_ETH40G_B2_RX1
DP_ETH40G_B2_RX2
DP_ETH40G_B2_TX1
DP_ETH40G_B2_TX2
DP_ETH40G_B2_TX1
DP_ETH40G_B2_TX2
DP_ETH40G_B2_RX2
DP_ETH40G_B2_RX1
DP_ETH40G_B2_TX3
DP_ETH40G_B2_TX0
DP_ETH10G_B2_TX2
116
CLOUD SERVER INFRASTRUCTURE ENGINEERING
 
11/24/2014
-16/11
100 OHM
603CH
1%
603CH
1%100 OHM
10 KOHM
603
BOM_IGNORE
CH
1%
BOM_IGNORE
603CH
1%10 KOHM
P3V3_B2_QSFP
100 OHM1%
CH603
BOM_IGNORE
603CH
1%10 KOHM
SM
BOM_IGNORE 100 OHM603 1%CH
BOM_IGNORE
100 OHM603
BOM_IGNORE
CONN P3V3_B2_QSFPP3V3_B2_QSFP
SM
BOM_IGNORE
X812373-001BOM_IGNORE
10 KOHM
100 PF
50 VNPO402
5%
402
EMPTY
6030 OHM 5%
10%
402X5R25 V
0.1 UF
BOM_IGNORE
2.2 A
FB
0.035DCR
30 OHM
402
5%CH6030 OHM
X812373-001
EMPTY
402
BOM_IGNORE
FB30 OHM
2.2 A 402
0.035DCR
BOM_IGNORE
402
10%0.1 UF
X5R25 V 5%
100 PF
NPO50 V
402
603CH
1%10 KOHM
BOM_IGNORE
100 OHM1%
CH603
1%
CH603
BOM_IGNORE
603CH
1%100 OHM
603
CH
1%10 KOHM
603
CH
1%10 KOHM
100 OHM1%
CH603
BOM_IGNORE
603CH
1%10 KOHM 10 KOHM1%
CH603
10 KOHM
1%
CH603
BOM_IGNORE
10 KOHM
1%
CH603
BOM_IGNORE
P3V3_B2_QSFP
P3V3_B2_QSFP
P3V3_B2_QSFP
CONN
SFP_RCPT_20P
SFP_HSNG_20P
CONN
TH
X881931-001
P3V3_B2_QSFP
TH
X881927-001
603CH
1%100 OHM
CH
5%
X881930-001
SM
0 OHM603 CH
1%CH
VOLTAGE=3.3
VOLTAGE=3.3
R31 R33
R30 R32
R35
R34
J29
R39
J28
FB3
R56R54
R57R55
R53
R52R50
R51
R48
R49
J17
J18
R46
C12C11
FS4
R45
FB4
C10
R40
R41
FS3
C9
J19
R43
R37
7C2 
7C6 
10B4 
7D6 
7C3 
7C6 
7D6 
7C3 
7D3 
7D6 
7D3 
7D6 
7C6 
7C3 
7C3 
7C6 
10B4 9C7 
10B4 3D6 
10B4 
10B4 
7D3 
10B4 
10B4 
10B4 
SKU_B2_ID0
SKU_B2_ID1
SKU_B2_ID2
PSU_B2_ALERT_N
BLADE_B2_EN1
ETH40G_B2_PRES_N
ETH40G_B2_TX0P
ETH10G_B2_TXP
ETH40G_B2_RX0N
ETH10G_B2_RXN
ETH10G_B2_SDA
SKU_B2_ID2
BLADE_B2_EN1
ETH10G_B2_SCL
ETH10G_B2_SDA
ETH10G_B2_TX_DIS
ETH10G_B2_TX_FAULT
ETH10G_B2_TXN
ETH10G_B2_TXP
ETH10G_B2_RXN
ETH10G_B2_RXP
P3V3_10G_B2_VCCR
P3V3_10G_B2_VCCT
ETH10G_B2_SDA
ETH10G_B2_SCL
ETH10G_B2_TX_FAULT
ETH10G_B2_TX_DIS
ETH10G_B2_RS0
ETH10G_B2_RS1
P3V3_10G_B2_VCCR
P3V3_10G_B2_VCCT
ETH10G_B2_RS1
ETH10G_B2_RXP
ETH40G_B2_TX3P
ETH40G_B2_RX1P
ETH40G_B2_RX2P
ETH40G_B2_TX3N
ETH40G_B2_RX3P
ETH40G_B2_TX2P
ETH40G_B2_TX1P
ETH40G_B2_TX2N
ETH40G_B2_TX1N
ETH40G_B2_RX2N
ETH40G_B2_RX1N
ETH40G_B2_RX3N
ETH10G_B2_TXN
SERIAL_B2_TX2
ETH10G_B2_RS0
ETH10G_B2_RX_LOS
ETH10G_B2_MOD_ABS
SKU_B2_ID1
SERIAL_B2_RX1
SERIAL_B2_RX2
PSU_B2_ALERT_N
ETH10G_B2_RX_LOS
ETH10G_B2_MOD_ABS
SERIAL_B2_TX1
SKU_B2_ID0
ETH40G_B2_SCL
ETH10G_B2_PRES_N
BLADE_B2_MATED_N<2>
ETH40G_B2_TX0N
ETH10G_B2_SCL
ETH40G_B2_SDA
ETH40G_B2_RX0P
2
1
2
1
2
1
2
1
2
1
2
1
2
1
1 2
1
B5
H2
F3
C5
J4
E1
I2
F4
2
1
2
1
1
2
1
2
1
21
2
1
2
1
22
1
2
1
2
1
2
6
12
13
7
9
8
5
4
19
18
3
2
15
16
10
11
14
1
17
20
1
10
11
12
13
14
15
16
17
18
19
2
20
3
4
5
6
7
8
9
1
2
1
2
1
21
1 2
1 2
1 2
1
2
2
1 2
1 2
1
2
A1
A2
A3
A4
A5
A6
B1
B2
B3
B4
B6
C1
C2
C3
C4
C6
D1
D2
D3
D4
D5
D6
E3
E4
E5
E6
F1
F2
F5
F6
G1
G2
G4
G5
G6
H1
H3
H4
H5
H6
I1
I3
I4
I5
I6
J2
J6
21
E2
G3
1
2
IN
OUT
OUT
OUT
OUT
OUT
OUT
OUT
IN
IN
IN
IN
IN
IN
IN
IN
RCPT
AIRMAX57P
J6
J4
J2
I6
I5
I4
I3
I2
I1
H6
H5
H4
H3
H2
H1
G6
G5
G4
G3
G2
G1
F6
F5
F4
F3
F2
F1
E6
E5
E4
E3
E2
E1
D6
D5
D4
D3
D2
D1
C6
C5
C4
C3
C2
C1
B6
B5
B4
B3
B2
B1
A6
A5
A4
A3
A2
A1
1X2HDR
1X2HDR
IN
IN
IN
OUT
IN
OUT
GND20
GND19
GND18
GND17
GND16
GND15
GND14
GND13
GND12
GND11
GND10
GND9
GND8
GND7
GND6
GND5
GND4
GND3
GND2
GND1
VEET3
TD_N
TD_P
VEET2
VCCT
VCCR
VEER3
RD_P
RD_N
VEER2
VEER1
RS1
RX_ LOS
RS0
MOD_ABS
SCL
SDA
TX_DISABLE
TX_FAULT
VEET1
8 7 6 5 4 3 2 1
D
C
B
A
DATE:
OFREVISION:DRAWING NUMBER:
12345678
A
B
C
D
PAGE:



QSFP+ VCC RX FILTER
QSFP+ HOUSING W/O HEATSINK
X89416-001
40G QSFP+ CONNECTOR
QSFP+ VCC FILTER
QSFP+ VCC TX FILTER
QSFP+ MISC PU/PD
SKU_ID2 TIED TO QSFP+ RESETCYA IF QSFP+ REQUIRES A RESET
117
CLOUD SERVER INFRASTRUCTURE ENGINEERING
 
11/24/2014
-17/11
BOM_IGNORE BOM_IGNORE
1
R65
100 OHM1%0.1 UF
R63
ETH40G_B2_MODSEL_N
ETH40G_B2_SDA
ETH40G_B2_RESET_N
ETH40G_B2_LPMODE
ETH40G_B2_INT_N
ETH40G_B2_SCL
1
0 OHM
BOM_IGNORECH603P3V3_B2_QSFP
P3V3_B2_QSFP
P3V3_40G_B2_VCC1
ETH40G_B2_RX3N
ETH40G_B2_RX3P
ETH40G_B2_PRES_NETH40G_B2_SDA
ETH40G_B2_SCL
P3V3_40G_B2_VCC_RX
P3V3_40G_B2_VCC1ETH40G_B2_RESET_N
ETH40G_B2_LPMODE
ETH40G_B2_TX3P
ETH40G_B2_TX2NETH40G_B2_TX3N
ETH40G_B2_TX1P
ETH40G_B2_TX0N
BOM_IGNORE
EMPTY
402
5%0 OHM CH603
BOM_IGNORE
402
0.035DCR
FB
2.2 A
30 OHM
10%
402X5R25 V
X5R25 V10%0.1 UF
4022.2 A
30 OHM
0.035DCR
FB
402
BOM_IGNORE
603 5%
CONN
603
1%10 KOHM 1%
10 KOHM
603
1%
BOM_IGNORE
603 CH0 OHM 5%
603CH
1%10 KOHM
603
CH
1%
10%0.1 UF
402X5R
25 V
0.035DCR
FB
402
30 OHM
CH0 OHM 5%603
X812373-001
402
EMPTY
BOM_IGNORE
VOLTAGE=3.3
VOLTAGE=3.3
ETH40G_B2_RX1N
0 OHM CH
10 KOHM
X812373-001
BOM_IGNORE
2.2 A
X812373-001
EMPTY
P3V3_B2_QSFP
ETH40G_B2_MODSEL_N
ETH40G_B2_INT_N
P3V3_B2_QSFP
TH
ETH40G_B2_TX0P
ETH40G_B2_TX2P
P3V3_40G_B2_VCC_TX
ETH40G_B2_RX2P
ETH40G_B2_RX2N
ETH40G_B2_RX0P
ETH40G_B2_RX0N
BOM_IGNORE
1%
CH CH603 CH
10 KOHM
5%
R70
1
2
R69
1
2
R661 2
R68
1
2
R67
1
2
R64
1
2
R62
1
13
16
19 20
26
1
4
7
35
31
27
8
9
18
17 22
15
14
24
25
12
372
3
33
5
6
10 29
R601 2
FS71 2
FB7
1 2
C17 1
2
C191
2
FB5
1 2
R581 2
C201
2
FB6
1 2
R591 2
FS51 2
FS61 2
R61
1 2
J21
1
10
11
12
2
3
4
5
6
8
9
38
34
32
30
28
23
21
ETH40G_B2_RX1P
ETH40G_B2_MODPRS_N
P3V3_40G_B2_VCC_TX
P3V3_40G_B2_VCC_RX
BOM_IGNORE
402
2
1 C24
X5R
2
1 C23
X5R6.3 V
603
20%
6.3 V
603
22 UF
22 UF20%
2
1C18
6.3 VX5R603
22 UF20%
P3V3_B2_QSFP
2
1 C27
X5R
20%22 UF
603
6.3 V
10 KOHM
6C8 
6D8 
6C5 
6D8 
6C8 6D8 
6C8 
6C5 6C8 
6D8 
6D8 
6D8 
6D8 
6C8 
6D5 
6D8 
36
7
J20
SFP_RCPT_38P
X886610-001
11
ETH40G_B2_TX1N
SM
CONN
SFP_HSNG_12P
X886611-001
SKU_B2_ID2
CH6032
6032
CHCH
1%100 OHM
2 603
8 7 6 5 4 3 2 1
D
C
B
A
DATE:
OFREVISION:DRAWING NUMBER:
12345678
A
B
C
D
PAGE:
IN
IN
IN
GND1
GND2
GND3
GND4
GND5
GND6
GND7
GND8
GND9
GND10
GND11
GND12
IN
OUT
OUT
OUT
OUT
IN
IN
IN
IN
GND_TX_6
TX1_N
TX1_P
GND_TX_5
TX3_N
TX3_P
GND_TX_4
LPMODE
VCC1
VCC_TX
INT_N
MODPRS_N
GND_RX_6
RX4_P
RX4_N
GND_RX_5
RX2_P
RX2_N
GND_RX_4GND_RX_3
RX1_N
RX1_P
GND_RX_2
RX3_P
RX3_N
SDA
SCL
VCC_RX
RESET_N
MODSEL_N
GND_TX_3
TX4_P
TX4_N
GND_TX_2
TX2_N
TX2_P
GND_TX_1
GND_RX_1
OUT
OUT
OUT
OUT
IN
OUT
QSFP+ VCC RX FILTER
QSFP+ HOUSING W/O HEATSINK
X89416-001
40G QSFP+ CONNECTOR
QSFP+ VCC FILTER
QSFP+ VCC TX FILTER
QSFP+ MISC PU/PD
SKU_ID2 TIED TO QSFP+ RESETCYA IF QSFP+ REQUIRES A RESET
117
CLOUD SERVER INFRASTRUCTURE ENGINEERING
 
11/24/2014
-17/11
BOM_IGNORE BOM_IGNORE
100 OHM1%0.1 UF
0 OHM
BOM_IGNORECH603P3V3_B2_QSFP
P3V3_B2_QSFP
BOM_IGNORE
EMPTY
402
5%0 OHM CH603
BOM_IGNORE
402
0.035DCR
FB
2.2 A
30 OHM
10%
402X5R
25 V
X5R25 V10%0.1 UF
4022.2 A
30 OHM
0.035DCR
FB
402
BOM_IGNORE
603 5%
CONN
603
1%10 KOHM 1%
10 KOHM
603
1%
BOM_IGNORE
603 CH0 OHM 5%
603CH
1%10 KOHM
603
CH
1%
10%0.1 UF
402X5R
25 V
0.035DCR
FB
402
30 OHM
CH0 OHM 5%603
X812373-001
402
EMPTY
BOM_IGNORE
0 OHM CH
10 KOHM
X812373-001
BOM_IGNORE
2.2 A
X812373-001
EMPTY
P3V3_B2_QSFP
P3V3_B2_QSFP
TH
BOM_IGNORE
1%
CH CH603 CH
10 KOHM
5%
BOM_IGNORE
402
X5R
X5R6.3 V
603
20%
6.3 V
603
22 UF
22 UF20%
6.3 VX5R
603
22 UF20%
P3V3_B2_QSFP
X5R
20%22 UF
603
6.3 V
10 KOHM
SFP_RCPT_38P
X886610-001 SM
CONN
SFP_HSNG_12P
X886611-001
CH603
603CHCH
1%100 OHM
603
VOLTAGE=3.3
VOLTAGE=3.3
R65R63
R70R69
R66
R68R67R64R62
R60
FS7FB7
C17
C19
FB5
R58
C20
FB6
R59
FS5
FS6
R61
J21
C24
C23
C18
C27
J20
6C8 
6D8 
6C5 
6D8 
6C8 6D8 
6C8 
6C5 6C8 
6D8 
6D8 
6D8 
6D8 
6C8 
6D5 
6D8 
ETH40G_B2_MODSEL_N
ETH40G_B2_SDA
ETH40G_B2_RESET_N
ETH40G_B2_LPMODE
ETH40G_B2_INT_N
ETH40G_B2_SCL
P3V3_40G_B2_VCC1
ETH40G_B2_RX3N
ETH40G_B2_RX3P
ETH40G_B2_PRES_NETH40G_B2_SDA
ETH40G_B2_SCL
P3V3_40G_B2_VCC_RX
P3V3_40G_B2_VCC1ETH40G_B2_RESET_N
ETH40G_B2_LPMODE
ETH40G_B2_TX3P
ETH40G_B2_TX2NETH40G_B2_TX3N
ETH40G_B2_TX1P
ETH40G_B2_TX0N
ETH40G_B2_RX1N
ETH40G_B2_MODSEL_N
ETH40G_B2_INT_N
ETH40G_B2_TX0P
ETH40G_B2_TX2P
P3V3_40G_B2_VCC_TX
ETH40G_B2_RX2P
ETH40G_B2_RX2N
ETH40G_B2_RX0P
ETH40G_B2_RX0N
ETH40G_B2_RX1P
ETH40G_B2_MODPRS_N
P3V3_40G_B2_VCC_TX
P3V3_40G_B2_VCC_RX
ETH40G_B2_TX1N
SKU_B2_ID2
11
1
2
1
2
1 2
1
2
1
2
1
2
1
13
16
19 20
26
1
4
7
35
31
27
8
9
18
17 22
15
14
24
25
12
372
3
33
5
6
10 29
1 2
1 21 2
1
2
1
21 2
1 2
1
21 2
1 2
1 2
1 2
1 2
1
10
11
12
2
3
4
5
6
8
9
38
34
32
30
28
23
21
2
1
2
1
2
1
2
1
36
7
11
2
22
IN
IN
IN
GND1
GND2
GND3
GND4
GND5
GND6
GND7
GND8
GND9
GND10
GND11
GND12
IN
OUT
OUT
OUT
OUT
IN
IN
IN
IN
GND_TX_6
TX1_N
TX1_P
GND_TX_5
TX3_N
TX3_P
GND_TX_4
LPMODE
VCC1
VCC_TX
INT_N
MODPRS_N
GND_RX_6
RX4_P
RX4_N
GND_RX_5
RX2_P
RX2_N
GND_RX_4GND_RX_3
RX1_N
RX1_P
GND_RX_2
RX3_P
RX3_N
SDA
SCL
VCC_RX
RESET_N
MODSEL_N
GND_TX_3
TX4_P
TX4_N
GND_TX_2
TX2_N
TX2_P
GND_TX_1
GND_RX_1
OUT
OUT
OUT
OUT
IN
OUT
8 7 6 5 4 3 2 1
D
C
B
A
DATE:
OFREVISION:DRAWING NUMBER:
12345678
A
B
C
D
PAGE:



SAS AIRMAX 3X6 CONNECTOR SAS MINI-HD CONNECTOR
118
CLOUD SERVER INFRASTRUCTURE ENGINEERING
 
11/24/2014
-18/11
10B7 
4D5 10B7 
10B7 
J6
J4
J2
I6
I5
I4
I3
I2
I1
H6
H5
H4
H3
H2
H1
G6
G5
G4
G3
G2
G1
F6
F5
F4
F3
F2
F1
E6
E5
E4
E3
E2
E1
D6
D5
D4
D3
D2
D1
C6
C5
C4
C3
C2
C1
B6
B5
B4
B3
B2
B1
A6
A5
A4
A3
A2
A1
J11
2
1
R1
9
8
7
6
5
4
3
2
10
1
2D9
2D8
2D7
2D6
2D5
2D4
2D3
2D2
2D1
2C9
2C8
2C7
2C6
2C5
2C4
2C3
2C2
2C1
2B9
2B8
2B7
2B6
2B5
2B4
2B3
2B2
2B1
2A9
2A8
2A7
2A6
2A5
2A4
2A3
2A2
2A1
1D9
1D8
1D7
1D6
1D5
1D4
1D3
1D2
1D1
1C9
1C8
1C7
1C6
1C5
1C4
1C3
1C2
1C1
1B9
1B8
1B7
1B6
1B5
1B4
1B3
1B2
1B1
1A9
1A8
1A7
1A6
1A5
1A4
1A3
1A2
1A1
J12
BLADE_B1_EN1
SERIAL_B1_RX1
SERIAL_B1_TX1
DP_SAS_B1_RX8
SAS_B1_TX1P
DP_SAS_B1_TX6
DP_SAS_B1_TX1
DP_SAS_B1_RX3
DP_SAS_B1_TX6
DP_SAS_B1_RX3
X881927-001
TH
JBOD_B1_MATED_N
DP_SAS_B1_TX1
DP_SAS_B1_RX8
DP_SAS_B1_RX1
DP_SAS_B1_RX4
DP_SAS_B1_RX6
DP_SAS_B1_RX1
DP_SAS_B1_TX3
DP_SAS_B1_RX4
DP_SAS_B1_TX5
DP_SAS_B1_RX6
DP_SAS_B1_TX8
DP_SAS_B1_TX3
DP_SAS_B1_TX5
DP_SAS_B1_TX8
DP_SAS_B1_TX2
DP_SAS_B1_TX4
DP_SAS_B1_TX7
DP_SAS_B1_TX2
DP_SAS_B1_RX2
DP_SAS_B1_TX4
DP_SAS_B1_RX5
DP_SAS_B1_TX7
DP_SAS_B1_RX7
DP_SAS_B1_RX2
DP_SAS_B1_RX5
DP_SAS_B1_RX7
DP_SAS_B1_RX2
DP_SAS_B1_RX2
DP_SAS_B1_RX4
DP_SAS_B1_RX4
DP_SAS_B1_RX1
DP_SAS_B1_RX1
DP_SAS_B1_RX3
DP_SAS_B1_RX3
DP_SAS_B1_TX2
DP_SAS_B1_TX2
DP_SAS_B1_TX4
DP_SAS_B1_TX4
DP_SAS_B1_TX1
DP_SAS_B1_TX1
DP_SAS_B1_TX3
DP_SAS_B1_TX3
DP_SAS_B1_RX6
DP_SAS_B1_RX6
DP_SAS_B1_RX8
DP_SAS_B1_RX8
DP_SAS_B1_RX5
DP_SAS_B1_RX5
DP_SAS_B1_RX7
DP_SAS_B1_RX7
DP_SAS_B1_TX6
DP_SAS_B1_TX6
DP_SAS_B1_TX8
DP_SAS_B1_TX8
DP_SAS_B1_TX5
DP_SAS_B1_TX5
DP_SAS_B1_TX7
DP_SAS_B1_TX7
SAS_B1_TX6P
SAS_B1_TX1N
SAS_B1_RX3P
SAS_B1_TX6N
SAS_B1_RX8P
SAS_B1_RX3N
SAS_B1_RX8N
SAS_B1_RX1P
SAS_B1_RX4P
SAS_B1_RX6P
SAS_B1_RX1N
SAS_B1_TX3P
SAS_B1_RX4N
SAS_B1_TX5P
SAS_B1_RX6N
SAS_B1_TX8P
SAS_B1_TX3N
SAS_B1_TX5N
SAS_B1_TX8N
SAS_B1_TX2P
SAS_B1_TX4P
SAS_B1_TX7P
SAS_B1_TX2N
SAS_B1_RX2P
SAS_B1_TX4N
SAS_B1_RX5P
SAS_B1_TX7N
SAS_B1_RX7P
SAS_B1_RX2N
SAS_B1_RX5N
SAS_B1_RX7N
SAS_B1_RX2P
SAS_B1_RX2N
SAS_B1_RX4P
SAS_B1_RX4N
SAS_B1_RX1P
SAS_B1_RX1N
SAS_B1_RX3P
SAS_B1_RX3N
SAS_B1_TX2P
SAS_B1_TX2N
SAS_B1_TX4P
SAS_B1_TX4N
SAS_B1_TX1P
SAS_B1_TX1N
SAS_B1_TX3P
SAS_B1_TX3N
SAS_B1_RX6P
SAS_B1_RX6N
SAS_B1_RX8P
SAS_B1_RX8N
SAS_B1_RX5P
SAS_B1_RX5N
SAS_B1_RX7P
SAS_B1_RX7N
SAS_B1_TX6P
SAS_B1_TX6N
SAS_B1_TX8P
SAS_B1_TX8N
SAS_B1_TX5P
SAS_B1_TX5N
SAS_B1_TX7P
SAS_B1_TX7N
100 OHM1%
CH603
CONN CONN
X881929-001
TH
8 7 6 5 4 3 2 1
D
C
B
A
DATE:
OFREVISION:DRAWING NUMBER:
12345678
A
B
C
D
PAGE:
IN
OUT
IN
X2
MINI SAS
MT10
MT9
MT8
MT7
MT6
MT5
MT4
MT3
MT2
MT1
2D9
2D8
2D7
2D6
2D5
2D4
2D3
2D2
2D1
2C9
2C8
2C7
2C6
2C5
2C4
2C3
2C2
2C1
2B9
2B8
2B7
2B6
2B5
2B4
2B3
2B2
2B1
2A9
2A8
2A7
2A6
2A5
2A4
2A3
2A2
2A1
1D9
1D8
1D7
1D6
1D5
1D4
1D3
1D2
1D1
1C9
1C8
1C7
1C6
1C5
1C4
1C3
1C2
1C1
1B9
1B8
1B7
1B6
1B5
1B4
1B3
1B2
1B1
1A9
1A8
1A7
1A6
1A5
1A4
1A3
1A2
1A1
RCPT
AIRMAX57P
J6
J4
J2
I6
I5
I4
I3
I2
I1
H6
H5
H4
H3
H2
H1
G6
G5
G4
G3
G2
G1
F6
F5
F4
F3
F2
F1
E6
E5
E4
E3
E2
E1
D6
D5
D4
D3
D2
D1
C6
C5
C4
C3
C2
C1
B6
B5
B4
B3
B2
B1
A6
A5
A4
A3
A2
A1
SAS AIRMAX 3X6 CONNECTOR SAS MINI-HD CONNECTOR
DP_SAS_B1_RX8
DP_SAS_B1_TX6
DP_SAS_B1_TX1
DP_SAS_B1_RX3
DP_SAS_B1_TX6
DP_SAS_B1_RX3
DP_SAS_B1_TX1
DP_SAS_B1_RX8
DP_SAS_B1_RX1
DP_SAS_B1_RX4
DP_SAS_B1_RX6
DP_SAS_B1_RX1
DP_SAS_B1_TX3
DP_SAS_B1_RX4
DP_SAS_B1_TX5
DP_SAS_B1_RX6
DP_SAS_B1_TX8
DP_SAS_B1_TX3
DP_SAS_B1_TX5
DP_SAS_B1_TX8
DP_SAS_B1_TX2
DP_SAS_B1_TX4
DP_SAS_B1_TX7
DP_SAS_B1_TX2
DP_SAS_B1_RX2
DP_SAS_B1_TX4
DP_SAS_B1_RX5
DP_SAS_B1_TX7
DP_SAS_B1_RX7
DP_SAS_B1_RX2
DP_SAS_B1_RX5
DP_SAS_B1_RX7
DP_SAS_B1_RX2
DP_SAS_B1_RX2
DP_SAS_B1_RX4
DP_SAS_B1_RX4
DP_SAS_B1_RX1
DP_SAS_B1_RX1
DP_SAS_B1_RX3
DP_SAS_B1_RX3
DP_SAS_B1_TX2
DP_SAS_B1_TX2
DP_SAS_B1_TX4
DP_SAS_B1_TX4
DP_SAS_B1_TX1
DP_SAS_B1_TX1
DP_SAS_B1_TX3
DP_SAS_B1_TX3
DP_SAS_B1_RX6
DP_SAS_B1_RX6
DP_SAS_B1_RX8
DP_SAS_B1_RX8
DP_SAS_B1_RX5
DP_SAS_B1_RX5
DP_SAS_B1_RX7
DP_SAS_B1_RX7
DP_SAS_B1_TX6
DP_SAS_B1_TX6
DP_SAS_B1_TX8
DP_SAS_B1_TX8
DP_SAS_B1_TX5
DP_SAS_B1_TX5
DP_SAS_B1_TX7
DP_SAS_B1_TX7
118
CLOUD SERVER INFRASTRUCTURE ENGINEERING
 
11/24/2014
-18/11
X881927-001
TH
100 OHM1%
CH603
CONN CONN
X881929-001
TH
J11
R1
J12
10B7 
4D5 10B7 
10B7 
BLADE_B1_EN1
SERIAL_B1_RX1
SERIAL_B1_TX1
SAS_B1_TX1P
JBOD_B1_MATED_N
SAS_B1_TX6P
SAS_B1_TX1N
SAS_B1_RX3P
SAS_B1_TX6N
SAS_B1_RX8P
SAS_B1_RX3N
SAS_B1_RX8N
SAS_B1_RX1P
SAS_B1_RX4P
SAS_B1_RX6P
SAS_B1_RX1N
SAS_B1_TX3P
SAS_B1_RX4N
SAS_B1_TX5P
SAS_B1_RX6N
SAS_B1_TX8P
SAS_B1_TX3N
SAS_B1_TX5N
SAS_B1_TX8N
SAS_B1_TX2P
SAS_B1_TX4P
SAS_B1_TX7P
SAS_B1_TX2N
SAS_B1_RX2P
SAS_B1_TX4N
SAS_B1_RX5P
SAS_B1_TX7N
SAS_B1_RX7P
SAS_B1_RX2N
SAS_B1_RX5N
SAS_B1_RX7N
SAS_B1_RX2P
SAS_B1_RX2N
SAS_B1_RX4P
SAS_B1_RX4N
SAS_B1_RX1P
SAS_B1_RX1N
SAS_B1_RX3P
SAS_B1_RX3N
SAS_B1_TX2P
SAS_B1_TX2N
SAS_B1_TX4P
SAS_B1_TX4N
SAS_B1_TX1P
SAS_B1_TX1N
SAS_B1_TX3P
SAS_B1_TX3N
SAS_B1_RX6P
SAS_B1_RX6N
SAS_B1_RX8P
SAS_B1_RX8N
SAS_B1_RX5P
SAS_B1_RX5N
SAS_B1_RX7P
SAS_B1_RX7N
SAS_B1_TX6P
SAS_B1_TX6N
SAS_B1_TX8P
SAS_B1_TX8N
SAS_B1_TX5P
SAS_B1_TX5N
SAS_B1_TX7P
SAS_B1_TX7N
J6
J4
J2
I6
I5
I4
I3
I2
I1
H6
H5
H4
H3
H2
H1
G6
G5
G4
G3
G2
G1
F6
F5
F4
F3
F2
F1
E6
E5
E4
E3
E2
E1
D6
D5
D4
D3
D2
D1
C6
C5
C4
C3
C2
C1
B6
B5
B4
B3
B2
B1
A6
A5
A4
A3
A2
A1
2
1
9
8
7
6
5
4
3
2
10
1
2D9
2D8
2D7
2D6
2D5
2D4
2D3
2D2
2D1
2C9
2C8
2C7
2C6
2C5
2C4
2C3
2C2
2C1
2B9
2B8
2B7
2B6
2B5
2B4
2B3
2B2
2B1
2A9
2A8
2A7
2A6
2A5
2A4
2A3
2A2
2A1
1D9
1D8
1D7
1D6
1D5
1D4
1D3
1D2
1D1
1C9
1C8
1C7
1C6
1C5
1C4
1C3
1C2
1C1
1B9
1B8
1B7
1B6
1B5
1B4
1B3
1B2
1B1
1A9
1A8
1A7
1A6
1A5
1A4
1A3
1A2
1A1
IN
OUT
IN
X2
MINI SAS
MT10
MT9
MT8
MT7
MT6
MT5
MT4
MT3
MT2
MT1
2D9
2D8
2D7
2D6
2D5
2D4
2D3
2D2
2D1
2C9
2C8
2C7
2C6
2C5
2C4
2C3
2C2
2C1
2B9
2B8
2B7
2B6
2B5
2B4
2B3
2B2
2B1
2A9
2A8
2A7
2A6
2A5
2A4
2A3
2A2
2A1
1D9
1D8
1D7
1D6
1D5
1D4
1D3
1D2
1D1
1C9
1C8
1C7
1C6
1C5
1C4
1C3
1C2
1C1
1B9
1B8
1B7
1B6
1B5
1B4
1B3
1B2
1B1
1A9
1A8
1A7
1A6
1A5
1A4
1A3
1A2
1A1
RCPT
AIRMAX57P
J6
J4
J2
I6
I5
I4
I3
I2
I1
H6
H5
H4
H3
H2
H1
G6
G5
G4
G3
G2
G1
F6
F5
F4
F3
F2
F1
E6
E5
E4
E3
E2
E1
D6
D5
D4
D3
D2
D1
C6
C5
C4
C3
C2
C1
B6
B5
B4
B3
B2
B1
A6
A5
A4
A3
A2
A1
8 7 6 5 4 3 2 1
D
C
B
A
DATE:
OFREVISION:DRAWING NUMBER:
12345678
A
B
C
D
PAGE:



SAS AIRMAX 3X6 CONNECTOR SAS MINI-HD CONNECTOR
119
CLOUD SERVER INFRASTRUCTURE ENGINEERING
 
11/24/2014
-19/11
10B4 
6D5 10B4 
10B4 
2
1
R71
J6
J4
J2
I6
I5
I4
I3
I2
I1
H6
H5
H4
H3
H2
H1
G6
G5
G4
G3
G2
G1
F6
F5
F4
F3
F2
F1
E6
E5
E4
E3
E2
E1
D6
D5
D4
D3
D2
D1
C6
C5
C4
C3
C2
C1
B6
B5
B4
B3
B2
B1
A6
A5
A4
A3
A2
A1
J23
9
8
7
6
5
4
3
2
10
1
2D9
2D8
2D7
2D6
2D5
2D4
2D3
2D2
2D1
2C9
2C8
2C7
2C6
2C5
2C4
2C3
2C2
2C1
2B9
2B8
2B7
2B6
2B5
2B4
2B3
2B2
2B1
2A9
2A8
2A7
2A6
2A5
2A4
2A3
2A2
2A1
1D9
1D8
1D7
1D6
1D5
1D4
1D3
1D2
1D1
1C9
1C8
1C7
1C6
1C5
1C4
1C3
1C2
1C1
1B9
1B8
1B7
1B6
1B5
1B4
1B3
1B2
1B1
1A9
1A8
1A7
1A6
1A5
1A4
1A3
1A2
1A1
J24
BLADE_B2_EN1
SERIAL_B2_RX1
SERIAL_B2_TX1
SAS_B2_RX1P
SAS_B2_RX4P
SAS_B2_RX6P
SAS_B2_RX1N
SAS_B2_TX3P
SAS_B2_RX4N
SAS_B2_TX5P
SAS_B2_RX6N
SAS_B2_TX1P
JBOD_B2_MATED_N
DP_SAS_B2_TX7
DP_SAS_B2_TX7
DP_SAS_B2_TX5
DP_SAS_B2_TX5
DP_SAS_B2_TX8
DP_SAS_B2_TX8
DP_SAS_B2_TX6
DP_SAS_B2_TX6
DP_SAS_B2_RX7
DP_SAS_B2_RX7
DP_SAS_B2_RX5
DP_SAS_B2_RX5
DP_SAS_B2_RX8
DP_SAS_B2_RX8
DP_SAS_B2_RX6
DP_SAS_B2_RX6
DP_SAS_B2_TX3
DP_SAS_B2_TX3
DP_SAS_B2_TX1
DP_SAS_B2_TX1
DP_SAS_B2_TX4
DP_SAS_B2_TX4
DP_SAS_B2_TX2
DP_SAS_B2_TX2
DP_SAS_B2_RX3
DP_SAS_B2_RX3
DP_SAS_B2_RX1
DP_SAS_B2_RX1
DP_SAS_B2_RX4
DP_SAS_B2_RX4
DP_SAS_B2_RX2
DP_SAS_B2_RX2
DP_SAS_B2_RX7
DP_SAS_B2_RX5
DP_SAS_B2_RX2
DP_SAS_B2_RX7
DP_SAS_B2_TX7
DP_SAS_B2_RX5
DP_SAS_B2_TX4
DP_SAS_B2_RX2
DP_SAS_B2_TX2
DP_SAS_B2_TX7
DP_SAS_B2_TX4
DP_SAS_B2_TX2
DP_SAS_B2_TX8
DP_SAS_B2_TX5
DP_SAS_B2_TX3
DP_SAS_B2_TX8
DP_SAS_B2_RX6
DP_SAS_B2_TX5
DP_SAS_B2_RX4
DP_SAS_B2_TX3
DP_SAS_B2_RX1
DP_SAS_B2_RX6
DP_SAS_B2_RX4
DP_SAS_B2_RX1
DP_SAS_B2_RX8
DP_SAS_B2_RX3
DP_SAS_B2_RX8
DP_SAS_B2_TX6
DP_SAS_B2_RX3
DP_SAS_B2_TX1
DP_SAS_B2_TX6
DP_SAS_B2_TX1
100 OHM1%
CH603
X881927-001
CONN
TH
CONN
X881929-001
TH
SAS_B2_TX3N
SAS_B2_TX5N SAS_B2_RX2P SAS_B2_RX6P
SAS_B2_TX6P SAS_B2_RX2N SAS_B2_RX6N
SAS_B2_TX8N
SAS_B2_RX4P SAS_B2_RX8P
SAS_B2_TX1N SAS_B2_TX2P SAS_B2_RX4N SAS_B2_RX8N
SAS_B2_RX3P
SAS_B2_TX4P
SAS_B2_TX6N SAS_B2_TX7P
SAS_B2_RX8P
SAS_B2_RX1P SAS_B2_RX5P
SAS_B2_TX2N SAS_B2_RX1N SAS_B2_RX5N
SAS_B2_RX3N SAS_B2_RX2P
SAS_B2_TX4N SAS_B2_RX3P SAS_B2_RX7P
SAS_B2_RX5P SAS_B2_RX3N SAS_B2_RX7N
SAS_B2_TX7N
SAS_B2_RX8N SAS_B2_RX7P
SAS_B2_RX2N
SAS_B2_TX2P SAS_B2_TX6P
SAS_B2_RX5N SAS_B2_TX2N SAS_B2_TX6N
SAS_B2_RX7N SAS_B2_TX4P SAS_B2_TX8P
SAS_B2_TX4N SAS_B2_TX8N
SAS_B2_TX8P SAS_B2_TX1P SAS_B2_TX5P
SAS_B2_TX1N SAS_B2_TX5N
SAS_B2_TX3P SAS_B2_TX7P
SAS_B2_TX3N SAS_B2_TX7N
8 7 6 5 4 3 2 1
D
C
B
A
DATE:
OFREVISION:DRAWING NUMBER:
12345678
A
B
C
D
PAGE:
IN
OUT
IN
RCPT
AIRMAX57P
J6
J4
J2
I6
I5
I4
I3
I2
I1
H6
H5
H4
H3
H2
H1
G6
G5
G4
G3
G2
G1
F6
F5
F4
F3
F2
F1
E6
E5
E4
E3
E2
E1
D6
D5
D4
D3
D2
D1
C6
C5
C4
C3
C2
C1
B6
B5
B4
B3
B2
B1
A6
A5
A4
A3
A2
A1
X2
MINI SAS
MT10
MT9
MT8
MT7
MT6
MT5
MT4
MT3
MT2
MT1
2D9
2D8
2D7
2D6
2D5
2D4
2D3
2D2
2D1
2C9
2C8
2C7
2C6
2C5
2C4
2C3
2C2
2C1
2B9
2B8
2B7
2B6
2B5
2B4
2B3
2B2
2B1
2A9
2A8
2A7
2A6
2A5
2A4
2A3
2A2
2A1
1D9
1D8
1D7
1D6
1D5
1D4
1D3
1D2
1D1
1C9
1C8
1C7
1C6
1C5
1C4
1C3
1C2
1C1
1B9
1B8
1B7
1B6
1B5
1B4
1B3
1B2
1B1
1A9
1A8
1A7
1A6
1A5
1A4
1A3
1A2
1A1
SAS AIRMAX 3X6 CONNECTOR SAS MINI-HD CONNECTOR
DP_SAS_B2_TX7
DP_SAS_B2_TX7
DP_SAS_B2_TX5
DP_SAS_B2_TX5
DP_SAS_B2_TX8
DP_SAS_B2_TX8
DP_SAS_B2_TX6
DP_SAS_B2_TX6
DP_SAS_B2_RX7
DP_SAS_B2_RX7
DP_SAS_B2_RX5
DP_SAS_B2_RX5
DP_SAS_B2_RX8
DP_SAS_B2_RX8
DP_SAS_B2_RX6
DP_SAS_B2_RX6
DP_SAS_B2_TX3
DP_SAS_B2_TX3
DP_SAS_B2_TX1
DP_SAS_B2_TX1
DP_SAS_B2_TX4
DP_SAS_B2_TX4
DP_SAS_B2_TX2
DP_SAS_B2_TX2
DP_SAS_B2_RX3
DP_SAS_B2_RX3
DP_SAS_B2_RX1
DP_SAS_B2_RX1
DP_SAS_B2_RX4
DP_SAS_B2_RX4
DP_SAS_B2_RX2
DP_SAS_B2_RX2
DP_SAS_B2_RX7
DP_SAS_B2_RX5
DP_SAS_B2_RX2
DP_SAS_B2_RX7
DP_SAS_B2_TX7
DP_SAS_B2_RX5
DP_SAS_B2_TX4
DP_SAS_B2_RX2
DP_SAS_B2_TX2
DP_SAS_B2_TX7
DP_SAS_B2_TX4
DP_SAS_B2_TX2
DP_SAS_B2_TX8
DP_SAS_B2_TX5
DP_SAS_B2_TX3
DP_SAS_B2_TX8
DP_SAS_B2_RX6
DP_SAS_B2_TX5
DP_SAS_B2_RX4
DP_SAS_B2_TX3
DP_SAS_B2_RX1
DP_SAS_B2_RX6
DP_SAS_B2_RX4
DP_SAS_B2_RX1
DP_SAS_B2_RX8
DP_SAS_B2_RX3
DP_SAS_B2_RX8
DP_SAS_B2_TX6
DP_SAS_B2_RX3
DP_SAS_B2_TX1
DP_SAS_B2_TX6
DP_SAS_B2_TX1
119
CLOUD SERVER INFRASTRUCTURE ENGINEERING
 
11/24/2014
-19/11
100 OHM1%
CH603
X881927-001
CONN
TH
CONN
X881929-001
TH
R71
J23 J24
10B4 
6D5 10B4 
10B4 
BLADE_B2_EN1
SERIAL_B2_RX1
SERIAL_B2_TX1
SAS_B2_RX1P
SAS_B2_RX4P
SAS_B2_RX6P
SAS_B2_RX1N
SAS_B2_TX3P
SAS_B2_RX4N
SAS_B2_TX5P
SAS_B2_RX6N
SAS_B2_TX1P
JBOD_B2_MATED_N
SAS_B2_TX3N
SAS_B2_TX5N SAS_B2_RX2P SAS_B2_RX6P
SAS_B2_TX6P SAS_B2_RX2N SAS_B2_RX6N
SAS_B2_TX8N
SAS_B2_RX4P SAS_B2_RX8P
SAS_B2_TX1N SAS_B2_TX2P SAS_B2_RX4N SAS_B2_RX8N
SAS_B2_RX3P
SAS_B2_TX4P
SAS_B2_TX6N SAS_B2_TX7P
SAS_B2_RX8P
SAS_B2_RX1P SAS_B2_RX5P
SAS_B2_TX2N SAS_B2_RX1N SAS_B2_RX5N
SAS_B2_RX3N SAS_B2_RX2P
SAS_B2_TX4N SAS_B2_RX3P SAS_B2_RX7P
SAS_B2_RX5P SAS_B2_RX3N SAS_B2_RX7N
SAS_B2_TX7N
SAS_B2_RX8N SAS_B2_RX7P
SAS_B2_RX2N
SAS_B2_TX2P SAS_B2_TX6P
SAS_B2_RX5N SAS_B2_TX2N SAS_B2_TX6N
SAS_B2_RX7N SAS_B2_TX4P SAS_B2_TX8P
SAS_B2_TX4N SAS_B2_TX8N
SAS_B2_TX8P SAS_B2_TX1P SAS_B2_TX5P
SAS_B2_TX1N SAS_B2_TX5N
SAS_B2_TX3P SAS_B2_TX7P
SAS_B2_TX3N SAS_B2_TX7N
2
1
J6
J4
J2
I6
I5
I4
I3
I2
I1
H6
H5
H4
H3
H2
H1
G6
G5
G4
G3
G2
G1
F6
F5
F4
F3
F2
F1
E6
E5
E4
E3
E2
E1
D6
D5
D4
D3
D2
D1
C6
C5
C4
C3
C2
C1
B6
B5
B4
B3
B2
B1
A6
A5
A4
A3
A2
A1
9
8
7
6
5
4
3
2
10
1
2D9
2D8
2D7
2D6
2D5
2D4
2D3
2D2
2D1
2C9
2C8
2C7
2C6
2C5
2C4
2C3
2C2
2C1
2B9
2B8
2B7
2B6
2B5
2B4
2B3
2B2
2B1
2A9
2A8
2A7
2A6
2A5
2A4
2A3
2A2
2A1
1D9
1D8
1D7
1D6
1D5
1D4
1D3
1D2
1D1
1C9
1C8
1C7
1C6
1C5
1C4
1C3
1C2
1C1
1B9
1B8
1B7
1B6
1B5
1B4
1B3
1B2
1B1
1A9
1A8
1A7
1A6
1A5
1A4
1A3
1A2
1A1
IN
OUT
IN
RCPT
AIRMAX57P
J6
J4
J2
I6
I5
I4
I3
I2
I1
H6
H5
H4
H3
H2
H1
G6
G5
G4
G3
G2
G1
F6
F5
F4
F3
F2
F1
E6
E5
E4
E3
E2
E1
D6
D5
D4
D3
D2
D1
C6
C5
C4
C3
C2
C1
B6
B5
B4
B3
B2
B1
A6
A5
A4
A3
A2
A1
X2
MINI SAS
MT10
MT9
MT8
MT7
MT6
MT5
MT4
MT3
MT2
MT1
2D9
2D8
2D7
2D6
2D5
2D4
2D3
2D2
2D1
2C9
2C8
2C7
2C6
2C5
2C4
2C3
2C2
2C1
2B9
2B8
2B7
2B6
2B5
2B4
2B3
2B2
2B1
2A9
2A8
2A7
2A6
2A5
2A4
2A3
2A2
2A1
1D9
1D8
1D7
1D6
1D5
1D4
1D3
1D2
1D1
1C9
1C8
1C7
1C6
1C5
1C4
1C3
1C2
1C1
1B9
1B8
1B7
1B6
1B5
1B4
1B3
1B2
1B1
1A9
1A8
1A7
1A6
1A5
1A4
1A3
1A2
1A1
8 7 6 5 4 3 2 1
D
C
B
A
DATE:
OFREVISION:DRAWING NUMBER:
12345678
A
B
C
D
PAGE:



PDB EDGE CONNECTOR
5V CURRENT = 0.5A
USB BLADE2 HEADER
5V CURRENT = 0.5A
USB BLADE1 HEADER
MINI-FIT JR POWER CONNECTOR
1110
CLOUD SERVER INFRASTRUCTURE ENGINEERING
 
11/24/2014
-110/11
6C5 9C7 
6D5 9C7 
3D6 6D5 
3A8 6C5 
6B6 6C5 9C7 
3A8 6A6 6D5 2A8 4A6 4D5 
2A8 4C5 
2D6 4D5 
4D5 8C7 
4C5 8C7 
4B6 4C5 8C7 
2B8 
2C8 
2C8 3C8 
3C8 
3B8 
4
3
2
1
U3
4
3
2
1
U2
43
21
J27
S9
S8
S7S6
S5
S4
S3
S2
S12
S11
S10
S1
P9-P12
P5-P8
P29-P32
P25-P28
P21-P24
P17-P20P13-P16
P1-P4
U1
SERIAL_B2_TX1
SERIAL_B2_RX1
SERIAL_B2_RX2
SERIAL_B2_TX2
BLADE_B2_EN1
PSU_B2_ALERT_N
BOM_IGNORE
SM
PSU_B1_ALERT_N
SERIAL_B1_TX2
X883311-001
SERIAL_B1_RX2
TH
TH
P12V
P12V
TH
X02123-002
CONN
P12V
SERIAL_B1_RX1
SERIAL_B1_TX1
BLADE_B1_EN1
P5V_USB_B1
USB_B1_P
USB_B1_N USB_B2_P
USB_B2_N
P5V_USB_B2
8 7 6 5 4 3 2 1
D
C
B
A
DATE:
OFREVISION:DRAWING NUMBER:
12345678
A
B
C
D
PAGE:
OUT
OUT
IN
OUT
IN
IN
BI
BI
1X4HDR
BI
BI
1X4HDR
IN
OUT
OUT
OUT
IN
OUT
2X2HDR
IN
OUT
HPCE EDGE CONN
S12
S11
S10
S9
S8
S7S6
S5
S4
S3
S2
S1
P29-P32
P25-P28
P21-P24
P17-P20P13-P16
P9-P12
P5-P8
P1-P4
PDB EDGE CONNECTOR
5V CURRENT = 0.5A
USB BLADE2 HEADER
5V CURRENT = 0.5A
USB BLADE1 HEADER
MINI-FIT JR POWER CONNECTOR
1110
CLOUD SERVER INFRASTRUCTURE ENGINEERING
 
11/24/2014
-110/11
BOM_IGNORE
SMX883311-001
TH
TH
P12V
P12V
TH
X02123-002
CONN
P12V
U3
U2
J27
U1
6C5 9C7 
6D5 9C7 
3D6 6D5 
3A8 6C5 
6B6 6C5 9C7 
3A8 6A6 6D5 2A8 4A6 4D5 
2A8 4C5 
2D6 4D5 
4D5 8C7 
4C5 8C7 
4B6 4C5 8C7 
2B8 
2C8 
2C8 3C8 
3C8 
3B8 
SERIAL_B2_TX1
SERIAL_B2_RX1
SERIAL_B2_RX2
SERIAL_B2_TX2
BLADE_B2_EN1
PSU_B2_ALERT_NPSU_B1_ALERT_N
SERIAL_B1_TX2
SERIAL_B1_RX2
SERIAL_B1_RX1
SERIAL_B1_TX1
BLADE_B1_EN1
P5V_USB_B1
USB_B1_P
USB_B1_N USB_B2_P
USB_B2_N
P5V_USB_B2
4
3
2
1
4
3
2
1
43
21
S9
S8
S7S6
S5
S4
S3
S2
S12
S11
S10
S1
P9-P12
P5-P8
P29-P32
P25-P28
P21-P24
P17-P20P13-P16
P1-P4
OUT
OUT
IN
OUT
IN
IN BI
BI
1X4HDR
BI
BI
1X4HDR
IN
OUT
OUT
OUT
IN
OUT
2X2HDR
IN
OUT
HPCE EDGE CONN
S12
S11
S10
S9
S8
S7S6
S5
S4
S3
S2
S1
P29-P32
P25-P28
P21-P24
P17-P20P13-P16
P9-P12
P5-P8
P1-P4
8 7 6 5 4 3 2 1
D
C
B
A
DATE:
OFREVISION:DRAWING NUMBER:
12345678
A
B
C
D
PAGE:



BLADE 2 GUIDE PINSBLADE 1 GUIDE PINS
1111
CLOUD SERVER INFRASTRUCTURE ENGINEERING
 
11/24/2014
-111/11
MH2
MH3 MH6
STD_276P138STD_276P138
STD_276P138
STD_276P138
STD_276P138
9
EMPTY
BOM_IGNORE
GND=1,2,3,4,5,6,7,8
GND=1,2,3,4,5,6,7,8
BOM_IGNORE
EMPTY
9
MH4
9
MH5
EMPTY
BOM_IGNORE
GND=1,2,3,4,5,6,7,8
BOM_IGNORE
GND=1,2,3,4,5,6,7,8
9
EMPTY
9
EMPTY
BOM_IGNORE
GND=1,2,3,4,5,6,7,8
STD_276P138
GND=1,2,3,4,5,6,7,8
BOM_IGNORE
MH1
9
EMPTY
1
J22
1
J15
1
J10
1
J3
X863845-001
X863845-001
X863845-001
TH
TH
TH
TH
X863845-001
8 7 6 5 4 3 2 1
D
C
B
A
DATE:
OFREVISION:DRAWING NUMBER:
12345678
A
B
C
D
PAGE:
GUIDE-PIN
GND
GUIDE-PIN
GND
GUIDE-PIN
GND
NC9
MTG_HOLE
NC9
MTG_HOLE
NC9
MTG_HOLE
NC9
MTG_HOLE
NC9
MTG_HOLE
NC9
MTG_HOLE
GUIDE-PIN
GND
BLADE 2 GUIDE PINSBLADE 1 GUIDE PINS
1111
CLOUD SERVER INFRASTRUCTURE ENGINEERING
 
11/24/2014
-111/11
STD_276P138STD_276P138
STD_276P138
STD_276P138
STD_276P138
EMPTY
BOM_IGNORE
GND=1,2,3,4,5,6,7,8
GND=1,2,3,4,5,6,7,8
BOM_IGNORE
EMPTY
EMPTY
BOM_IGNORE
GND=1,2,3,4,5,6,7,8
BOM_IGNORE
GND=1,2,3,4,5,6,7,8
EMPTY EMPTY
BOM_IGNORE
GND=1,2,3,4,5,6,7,8
STD_276P138
GND=1,2,3,4,5,6,7,8
BOM_IGNORE
EMPTY
X863845-001
X863845-001
X863845-001
TH
TH
TH
TH
X863845-001
MH2
MH3 MH6
MH4
MH5
MH1
J22
J15
J10
J3
9
9
9
9 9
9
1
1
1
1
GUIDE-PIN
GND
GUIDE-PIN
GND
GUIDE-PIN
GND
NC9
MTG_HOLE
NC9
MTG_HOLE
NC9
MTG_HOLE
NC9
MTG_HOLE
NC9
MTG_HOLE
NC9
MTG_HOLE
GUIDE-PIN
GND
8 7 6 5 4 3 2 1
D
C
B
A
DATE:
OFREVISION:DRAWING NUMBER:
12345678
A
B
C
D
PAGE: